FILE_TYPE = MACRO_DRAWING;
SET COLOR_WIRE YELLOW;
SET COLOR_PROP ORANGE;
SET COLOR_DOT WHITE;
SET COLOR_ARC YELLOW;
SET COLOR_BODY GREEN;
SET COLOR_NOTE PURPLE;
SET PROP_DISPLAY VALUE;
SET PAGE_NUMBER P20;
FORCEADD GENOA_SP5..36
(-4425 3575);
FORCEPROP 1 LAST LOCATION U25
J 0
(-5070 6406);
DISPLAY 0.489362 (-5070 6406);
PAINT SKYBLUE (-5070 6406);
FORCEPROP 0 LAST $SEC 36
J 0
(-5050 6550);
DISPLAY 0.680851 (-5050 6550);
PAINT MONO (-5050 6550);
DISPLAY INVISIBLE (-5050 6550);
FORCEPROP 0 LAST CDS_SEC 36
J 0
(-5050 6550);
DISPLAY 1.021277 (-5050 6550);
DISPLAY INVISIBLE (-5050 6550);
FORCEPROP 0 LASTPIN (-5225 2950) $PN BC5
J 2
(-5235 2960);
DISPLAY 0.489362 (-5235 2960);
PAINT MONO (-5235 2960);
FORCEPROP 0 LASTPIN (-5225 2900) $PN BD6
J 2
(-5235 2910);
DISPLAY 0.489362 (-5235 2910);
PAINT MONO (-5235 2910);
FORCEPROP 0 LASTPIN (-5225 1800) $PN BF6
J 2
(-5235 1810);
DISPLAY 0.489362 (-5235 1810);
PAINT MONO (-5235 1810);
FORCEPROP 0 LASTPIN (-5225 1750) $PN BG5
J 2
(-5235 1760);
DISPLAY 0.489362 (-5235 1760);
PAINT MONO (-5235 1760);
FORCEPROP 0 LASTPIN (-5225 2100) $PN AT7
J 2
(-5235 2110);
DISPLAY 0.489362 (-5235 2110);
PAINT MONO (-5235 2110);
FORCEPROP 0 LASTPIN (-5225 2000) $PN AU7
J 2
(-5235 2010);
DISPLAY 0.489362 (-5235 2010);
PAINT MONO (-5235 2010);
FORCEPROP 0 LASTPIN (-5225 2800) $PN AU5
J 2
(-5235 2810);
DISPLAY 0.489362 (-5235 2810);
PAINT MONO (-5235 2810);
FORCEPROP 0 LASTPIN (-5225 2750) $PN AV7
J 2
(-5235 2760);
DISPLAY 0.489362 (-5235 2760);
PAINT MONO (-5235 2760);
FORCEPROP 0 LASTPIN (-5225 2650) $PN BN7
J 2
(-5235 2660);
DISPLAY 0.489362 (-5235 2660);
PAINT MONO (-5235 2660);
FORCEPROP 0 LASTPIN (-5225 1650) $PN AV6
J 2
(-5235 1660);
DISPLAY 0.489362 (-5235 1660);
PAINT MONO (-5235 1660);
FORCEPROP 0 LASTPIN (-5225 1600) $PN AW7
J 2
(-5235 1610);
DISPLAY 0.489362 (-5235 1610);
PAINT MONO (-5235 1610);
FORCEPROP 0 LASTPIN (-5225 1500) $PN BP7
J 2
(-5235 1510);
DISPLAY 0.489362 (-5235 1510);
PAINT MONO (-5235 1510);
FORCEPROP 0 LASTPIN (-5225 3800) $PN AW5
J 2
(-5235 3810);
DISPLAY 0.489362 (-5235 3810);
PAINT MONO (-5235 3810);
FORCEPROP 0 LASTPIN (-5225 3750) $PN AY6
J 2
(-5235 3760);
DISPLAY 0.489362 (-5235 3760);
PAINT MONO (-5235 3760);
FORCEPROP 0 LASTPIN (-5225 3700) $PN AY7
J 2
(-5235 3710);
DISPLAY 0.489362 (-5235 3710);
PAINT MONO (-5235 3710);
FORCEPROP 0 LASTPIN (-5225 3650) $PN BA7
J 2
(-5235 3660);
DISPLAY 0.489362 (-5235 3660);
PAINT MONO (-5235 3660);
FORCEPROP 0 LASTPIN (-5225 3600) $PN BA5
J 2
(-5235 3610);
DISPLAY 0.489362 (-5235 3610);
PAINT MONO (-5235 3610);
FORCEPROP 0 LASTPIN (-5225 3550) $PN BB6
J 2
(-5235 3560);
DISPLAY 0.489362 (-5235 3560);
PAINT MONO (-5235 3560);
FORCEPROP 0 LASTPIN (-5225 3500) $PN BB7
J 2
(-5235 3510);
DISPLAY 0.489362 (-5235 3510);
PAINT MONO (-5235 3510);
FORCEPROP 0 LASTPIN (-3625 2350) $PN AJ5
J 0
(-3615 2360);
DISPLAY 0.489362 (-3615 2360);
PAINT MONO (-3615 2360);
FORCEPROP 0 LASTPIN (-3625 2300) $PN AK7
J 0
(-3615 2310);
DISPLAY 0.489362 (-3615 2310);
PAINT MONO (-3615 2310);
FORCEPROP 0 LASTPIN (-3625 2250) $PN AK6
J 0
(-3615 2260);
DISPLAY 0.489362 (-3615 2260);
PAINT MONO (-3615 2260);
FORCEPROP 0 LASTPIN (-3625 2200) $PN AL7
J 0
(-3615 2210);
DISPLAY 0.489362 (-3615 2210);
PAINT MONO (-3615 2210);
FORCEPROP 0 LASTPIN (-3625 2150) $PN AN5
J 0
(-3615 2160);
DISPLAY 0.489362 (-3615 2160);
PAINT MONO (-3615 2160);
FORCEPROP 0 LASTPIN (-3625 2100) $PN AP7
J 0
(-3615 2110);
DISPLAY 0.489362 (-3615 2110);
PAINT MONO (-3615 2110);
FORCEPROP 0 LASTPIN (-3625 2050) $PN AP6
J 0
(-3615 2060);
DISPLAY 0.489362 (-3615 2060);
PAINT MONO (-3615 2060);
FORCEPROP 0 LASTPIN (-3625 2000) $PN AR7
J 0
(-3615 2010);
DISPLAY 0.489362 (-3615 2010);
PAINT MONO (-3615 2010);
FORCEPROP 0 LASTPIN (-3625 5950) $PN E5
J 0
(-3615 5960);
DISPLAY 0.489362 (-3615 5960);
PAINT MONO (-3615 5960);
FORCEPROP 0 LASTPIN (-3625 5900) $PN F7
J 0
(-3615 5910);
DISPLAY 0.489362 (-3615 5910);
PAINT MONO (-3615 5910);
FORCEPROP 0 LASTPIN (-3625 5850) $PN F6
J 0
(-3615 5860);
DISPLAY 0.489362 (-3615 5860);
PAINT MONO (-3615 5860);
FORCEPROP 0 LASTPIN (-3625 5800) $PN G7
J 0
(-3615 5810);
DISPLAY 0.489362 (-3615 5810);
PAINT MONO (-3615 5810);
FORCEPROP 0 LASTPIN (-3625 5750) $PN J5
J 0
(-3615 5760);
DISPLAY 0.489362 (-3615 5760);
PAINT MONO (-3615 5760);
FORCEPROP 0 LASTPIN (-3625 5700) $PN K7
J 0
(-3615 5710);
DISPLAY 0.489362 (-3615 5710);
PAINT MONO (-3615 5710);
FORCEPROP 0 LASTPIN (-3625 5650) $PN K6
J 0
(-3615 5660);
DISPLAY 0.489362 (-3615 5660);
PAINT MONO (-3615 5660);
FORCEPROP 0 LASTPIN (-3625 5600) $PN L7
J 0
(-3615 5610);
DISPLAY 0.489362 (-3615 5610);
PAINT MONO (-3615 5610);
FORCEPROP 0 LASTPIN (-3625 5500) $PN L5
J 0
(-3615 5510);
DISPLAY 0.489362 (-3615 5510);
PAINT MONO (-3615 5510);
FORCEPROP 0 LASTPIN (-3625 5450) $PN M7
J 0
(-3615 5460);
DISPLAY 0.489362 (-3615 5460);
PAINT MONO (-3615 5460);
FORCEPROP 0 LASTPIN (-3625 5400) $PN M6
J 0
(-3615 5410);
DISPLAY 0.489362 (-3615 5410);
PAINT MONO (-3615 5410);
FORCEPROP 0 LASTPIN (-3625 5350) $PN N7
J 0
(-3615 5360);
DISPLAY 0.489362 (-3615 5360);
PAINT MONO (-3615 5360);
FORCEPROP 0 LASTPIN (-3625 5300) $PN R5
J 0
(-3615 5310);
DISPLAY 0.489362 (-3615 5310);
PAINT MONO (-3615 5310);
FORCEPROP 0 LASTPIN (-3625 5250) $PN T7
J 0
(-3615 5260);
DISPLAY 0.489362 (-3615 5260);
PAINT MONO (-3615 5260);
FORCEPROP 0 LASTPIN (-3625 5200) $PN T6
J 0
(-3615 5210);
DISPLAY 0.489362 (-3615 5210);
PAINT MONO (-3615 5210);
FORCEPROP 0 LASTPIN (-3625 5150) $PN U7
J 0
(-3615 5160);
DISPLAY 0.489362 (-3615 5160);
PAINT MONO (-3615 5160);
FORCEPROP 0 LASTPIN (-3625 5050) $PN U5
J 0
(-3615 5060);
DISPLAY 0.489362 (-3615 5060);
PAINT MONO (-3615 5060);
FORCEPROP 0 LASTPIN (-3625 5000) $PN V7
J 0
(-3615 5010);
DISPLAY 0.489362 (-3615 5010);
PAINT MONO (-3615 5010);
FORCEPROP 0 LASTPIN (-3625 4950) $PN V6
J 0
(-3615 4960);
DISPLAY 0.489362 (-3615 4960);
PAINT MONO (-3615 4960);
FORCEPROP 0 LASTPIN (-3625 4900) $PN W7
J 0
(-3615 4910);
DISPLAY 0.489362 (-3615 4910);
PAINT MONO (-3615 4910);
FORCEPROP 0 LASTPIN (-3625 4850) $PN AA5
J 0
(-3615 4860);
DISPLAY 0.489362 (-3615 4860);
PAINT MONO (-3615 4860);
FORCEPROP 0 LASTPIN (-3625 4800) $PN AB7
J 0
(-3615 4810);
DISPLAY 0.489362 (-3615 4810);
PAINT MONO (-3615 4810);
FORCEPROP 0 LASTPIN (-3625 4750) $PN AB6
J 0
(-3615 4760);
DISPLAY 0.489362 (-3615 4760);
PAINT MONO (-3615 4760);
FORCEPROP 0 LASTPIN (-3625 4700) $PN AC7
J 0
(-3615 4710);
DISPLAY 0.489362 (-3615 4710);
PAINT MONO (-3615 4710);
FORCEPROP 0 LASTPIN (-3625 4600) $PN AC5
J 0
(-3615 4610);
DISPLAY 0.489362 (-3615 4610);
PAINT MONO (-3615 4610);
FORCEPROP 0 LASTPIN (-3625 4550) $PN AD7
J 0
(-3615 4560);
DISPLAY 0.489362 (-3615 4560);
PAINT MONO (-3615 4560);
FORCEPROP 0 LASTPIN (-3625 4500) $PN AD6
J 0
(-3615 4510);
DISPLAY 0.489362 (-3615 4510);
PAINT MONO (-3615 4510);
FORCEPROP 0 LASTPIN (-3625 4450) $PN AE7
J 0
(-3615 4460);
DISPLAY 0.489362 (-3615 4460);
PAINT MONO (-3615 4460);
FORCEPROP 0 LASTPIN (-3625 4400) $PN AG5
J 0
(-3615 4410);
DISPLAY 0.489362 (-3615 4410);
PAINT MONO (-3615 4410);
FORCEPROP 0 LASTPIN (-3625 4350) $PN AH7
J 0
(-3615 4360);
DISPLAY 0.489362 (-3615 4360);
PAINT MONO (-3615 4360);
FORCEPROP 0 LASTPIN (-3625 4300) $PN AH6
J 0
(-3615 4310);
DISPLAY 0.489362 (-3615 4310);
PAINT MONO (-3615 4310);
FORCEPROP 0 LASTPIN (-3625 4250) $PN AJ7
J 0
(-3615 4260);
DISPLAY 0.489362 (-3615 4260);
PAINT MONO (-3615 4260);
FORCEPROP 0 LASTPIN (-5225 5950) $PN G5
J 2
(-5235 5960);
DISPLAY 0.489362 (-5235 5960);
PAINT MONO (-5235 5960);
FORCEPROP 0 LASTPIN (-5225 5850) $PN N5
J 2
(-5235 5860);
DISPLAY 0.489362 (-5235 5860);
PAINT MONO (-5235 5860);
FORCEPROP 0 LASTPIN (-5225 5750) $PN W5
J 2
(-5235 5760);
DISPLAY 0.489362 (-5235 5760);
PAINT MONO (-5235 5760);
FORCEPROP 0 LASTPIN (-5225 5650) $PN AE5
J 2
(-5235 5660);
DISPLAY 0.489362 (-5235 5660);
PAINT MONO (-5235 5660);
FORCEPROP 0 LASTPIN (-5225 5550) $PN AL5
J 2
(-5235 5560);
DISPLAY 0.489362 (-5235 5560);
PAINT MONO (-5235 5560);
FORCEPROP 0 LASTPIN (-5225 5450) $PN J7
J 2
(-5235 5460);
DISPLAY 0.489362 (-5235 5460);
PAINT MONO (-5235 5460);
FORCEPROP 0 LASTPIN (-5225 5350) $PN R7
J 2
(-5235 5360);
DISPLAY 0.489362 (-5235 5360);
PAINT MONO (-5235 5360);
FORCEPROP 0 LASTPIN (-5225 5250) $PN AA7
J 2
(-5235 5260);
DISPLAY 0.489362 (-5235 5260);
PAINT MONO (-5235 5260);
FORCEPROP 0 LASTPIN (-5225 5150) $PN AG7
J 2
(-5235 5160);
DISPLAY 0.489362 (-5235 5160);
PAINT MONO (-5235 5160);
FORCEPROP 0 LASTPIN (-5225 5050) $PN AN7
J 2
(-5235 5060);
DISPLAY 0.489362 (-5235 5060);
PAINT MONO (-5235 5060);
FORCEPROP 0 LASTPIN (-5225 5900) $PN H6
J 2
(-5235 5910);
DISPLAY 0.489362 (-5235 5910);
PAINT MONO (-5235 5910);
FORCEPROP 0 LASTPIN (-5225 5800) $PN P6
J 2
(-5235 5810);
DISPLAY 0.489362 (-5235 5810);
PAINT MONO (-5235 5810);
FORCEPROP 0 LASTPIN (-5225 5700) $PN Y6
J 2
(-5235 5710);
DISPLAY 0.489362 (-5235 5710);
PAINT MONO (-5235 5710);
FORCEPROP 0 LASTPIN (-5225 5600) $PN AF6
J 2
(-5235 5610);
DISPLAY 0.489362 (-5235 5610);
PAINT MONO (-5235 5610);
FORCEPROP 0 LASTPIN (-5225 5500) $PN AM6
J 2
(-5235 5510);
DISPLAY 0.489362 (-5235 5510);
PAINT MONO (-5235 5510);
FORCEPROP 0 LASTPIN (-5225 5400) $PN H7
J 2
(-5235 5410);
DISPLAY 0.489362 (-5235 5410);
PAINT MONO (-5235 5410);
FORCEPROP 0 LASTPIN (-5225 5300) $PN P7
J 2
(-5235 5310);
DISPLAY 0.489362 (-5235 5310);
PAINT MONO (-5235 5310);
FORCEPROP 0 LASTPIN (-5225 5200) $PN Y7
J 2
(-5235 5210);
DISPLAY 0.489362 (-5235 5210);
PAINT MONO (-5235 5210);
FORCEPROP 0 LASTPIN (-5225 5100) $PN AF7
J 2
(-5235 5110);
DISPLAY 0.489362 (-5235 5110);
PAINT MONO (-5235 5110);
FORCEPROP 0 LASTPIN (-5225 5000) $PN AM7
J 2
(-5235 5010);
DISPLAY 0.489362 (-5235 5010);
PAINT MONO (-5235 5010);
FORCEPROP 0 LASTPIN (-5225 2550) $PN BC7
J 2
(-5235 2560);
DISPLAY 0.489362 (-5235 2560);
PAINT MONO (-5235 2560);
FORCEPROP 0 LASTPIN (-5225 2450) $PN BM7
J 2
(-5235 2460);
DISPLAY 0.489362 (-5235 2460);
PAINT MONO (-5235 2460);
FORCEPROP 0 LASTPIN (-5225 2400) $PN BN5
J 2
(-5235 2410);
DISPLAY 0.489362 (-5235 2410);
PAINT MONO (-5235 2410);
FORCEPROP 0 LASTPIN (-5225 2300) $PN BP6
J 2
(-5235 2310);
DISPLAY 0.489362 (-5235 2310);
PAINT MONO (-5235 2310);
FORCEPROP 0 LASTPIN (-5225 1400) $PN BL5
J 2
(-5235 1410);
DISPLAY 0.489362 (-5235 1410);
PAINT MONO (-5235 1410);
FORCEPROP 0 LASTPIN (-5225 1350) $PN BM6
J 2
(-5235 1360);
DISPLAY 0.489362 (-5235 1360);
PAINT MONO (-5235 1360);
FORCEPROP 0 LASTPIN (-5225 1250) $PN BR5
J 2
(-5235 1260);
DISPLAY 0.489362 (-5235 1260);
PAINT MONO (-5235 1260);
FORCEPROP 0 LASTPIN (-5225 3400) $PN BG7
J 2
(-5235 3410);
DISPLAY 0.489362 (-5235 3410);
PAINT MONO (-5235 3410);
FORCEPROP 0 LASTPIN (-5225 3350) $PN BH7
J 2
(-5235 3360);
DISPLAY 0.489362 (-5235 3360);
PAINT MONO (-5235 3360);
FORCEPROP 0 LASTPIN (-5225 3300) $PN BH6
J 2
(-5235 3310);
DISPLAY 0.489362 (-5235 3310);
PAINT MONO (-5235 3310);
FORCEPROP 0 LASTPIN (-5225 3250) $PN BJ5
J 2
(-5235 3260);
DISPLAY 0.489362 (-5235 3260);
PAINT MONO (-5235 3260);
FORCEPROP 0 LASTPIN (-5225 3200) $PN BJ7
J 2
(-5235 3210);
DISPLAY 0.489362 (-5235 3210);
PAINT MONO (-5235 3210);
FORCEPROP 0 LASTPIN (-5225 3150) $PN BK7
J 2
(-5235 3160);
DISPLAY 0.489362 (-5235 3160);
PAINT MONO (-5235 3160);
FORCEPROP 0 LASTPIN (-5225 3100) $PN BK6
J 2
(-5235 3110);
DISPLAY 0.489362 (-5235 3110);
PAINT MONO (-5235 3110);
FORCEPROP 0 LASTPIN (-3625 1900) $PN BY6
J 0
(-3615 1910);
DISPLAY 0.489362 (-3615 1910);
PAINT MONO (-3615 1910);
FORCEPROP 0 LASTPIN (-3625 1850) $PN CA7
J 0
(-3615 1860);
DISPLAY 0.489362 (-3615 1860);
PAINT MONO (-3615 1860);
FORCEPROP 0 LASTPIN (-3625 1800) $PN CA5
J 0
(-3615 1810);
DISPLAY 0.489362 (-3615 1810);
PAINT MONO (-3615 1810);
FORCEPROP 0 LASTPIN (-3625 1750) $PN CB7
J 0
(-3615 1760);
DISPLAY 0.489362 (-3615 1760);
PAINT MONO (-3615 1760);
FORCEPROP 0 LASTPIN (-3625 1700) $PN BT6
J 0
(-3615 1710);
DISPLAY 0.489362 (-3615 1710);
PAINT MONO (-3615 1710);
FORCEPROP 0 LASTPIN (-3625 1650) $PN BU7
J 0
(-3615 1660);
DISPLAY 0.489362 (-3615 1660);
PAINT MONO (-3615 1660);
FORCEPROP 0 LASTPIN (-3625 1600) $PN BU5
J 0
(-3615 1610);
DISPLAY 0.489362 (-3615 1610);
PAINT MONO (-3615 1610);
FORCEPROP 0 LASTPIN (-3625 1550) $PN BV7
J 0
(-3615 1560);
DISPLAY 0.489362 (-3615 1560);
PAINT MONO (-3615 1560);
FORCEPROP 0 LASTPIN (-3625 4150) $PN CB6
J 0
(-3615 4160);
DISPLAY 0.489362 (-3615 4160);
PAINT MONO (-3615 4160);
FORCEPROP 0 LASTPIN (-3625 4100) $PN CC7
J 0
(-3615 4110);
DISPLAY 0.489362 (-3615 4110);
PAINT MONO (-3615 4110);
FORCEPROP 0 LASTPIN (-3625 4050) $PN CC5
J 0
(-3615 4060);
DISPLAY 0.489362 (-3615 4060);
PAINT MONO (-3615 4060);
FORCEPROP 0 LASTPIN (-3625 4000) $PN CD7
J 0
(-3615 4010);
DISPLAY 0.489362 (-3615 4010);
PAINT MONO (-3615 4010);
FORCEPROP 0 LASTPIN (-3625 3950) $PN CF6
J 0
(-3615 3960);
DISPLAY 0.489362 (-3615 3960);
PAINT MONO (-3615 3960);
FORCEPROP 0 LASTPIN (-3625 3900) $PN CG7
J 0
(-3615 3910);
DISPLAY 0.489362 (-3615 3910);
PAINT MONO (-3615 3910);
FORCEPROP 0 LASTPIN (-3625 3850) $PN CG5
J 0
(-3615 3860);
DISPLAY 0.489362 (-3615 3860);
PAINT MONO (-3615 3860);
FORCEPROP 0 LASTPIN (-3625 3800) $PN CH7
J 0
(-3615 3810);
DISPLAY 0.489362 (-3615 3810);
PAINT MONO (-3615 3810);
FORCEPROP 0 LASTPIN (-3625 3700) $PN CH6
J 0
(-3615 3710);
DISPLAY 0.489362 (-3615 3710);
PAINT MONO (-3615 3710);
FORCEPROP 0 LASTPIN (-3625 3650) $PN CJ7
J 0
(-3615 3660);
DISPLAY 0.489362 (-3615 3660);
PAINT MONO (-3615 3660);
FORCEPROP 0 LASTPIN (-3625 3600) $PN CJ5
J 0
(-3615 3610);
DISPLAY 0.489362 (-3615 3610);
PAINT MONO (-3615 3610);
FORCEPROP 0 LASTPIN (-3625 3550) $PN CK7
J 0
(-3615 3560);
DISPLAY 0.489362 (-3615 3560);
PAINT MONO (-3615 3560);
FORCEPROP 0 LASTPIN (-3625 3500) $PN CM6
J 0
(-3615 3510);
DISPLAY 0.489362 (-3615 3510);
PAINT MONO (-3615 3510);
FORCEPROP 0 LASTPIN (-3625 3450) $PN CN7
J 0
(-3615 3460);
DISPLAY 0.489362 (-3615 3460);
PAINT MONO (-3615 3460);
FORCEPROP 0 LASTPIN (-3625 3400) $PN CN5
J 0
(-3615 3410);
DISPLAY 0.489362 (-3615 3410);
PAINT MONO (-3615 3410);
FORCEPROP 0 LASTPIN (-3625 3350) $PN CP7
J 0
(-3615 3360);
DISPLAY 0.489362 (-3615 3360);
PAINT MONO (-3615 3360);
FORCEPROP 0 LASTPIN (-3625 3250) $PN CP6
J 0
(-3615 3260);
DISPLAY 0.489362 (-3615 3260);
PAINT MONO (-3615 3260);
FORCEPROP 0 LASTPIN (-3625 3200) $PN CR7
J 0
(-3615 3210);
DISPLAY 0.489362 (-3615 3210);
PAINT MONO (-3615 3210);
FORCEPROP 0 LASTPIN (-3625 3150) $PN CR5
J 0
(-3615 3160);
DISPLAY 0.489362 (-3615 3160);
PAINT MONO (-3615 3160);
FORCEPROP 0 LASTPIN (-3625 3100) $PN CT7
J 0
(-3615 3110);
DISPLAY 0.489362 (-3615 3110);
PAINT MONO (-3615 3110);
FORCEPROP 0 LASTPIN (-3625 3050) $PN CV6
J 0
(-3615 3060);
DISPLAY 0.489362 (-3615 3060);
PAINT MONO (-3615 3060);
FORCEPROP 0 LASTPIN (-3625 3000) $PN CW7
J 0
(-3615 3010);
DISPLAY 0.489362 (-3615 3010);
PAINT MONO (-3615 3010);
FORCEPROP 0 LASTPIN (-3625 2950) $PN CW5
J 0
(-3615 2960);
DISPLAY 0.489362 (-3615 2960);
PAINT MONO (-3615 2960);
FORCEPROP 0 LASTPIN (-3625 2900) $PN CY7
J 0
(-3615 2910);
DISPLAY 0.489362 (-3615 2910);
PAINT MONO (-3615 2910);
FORCEPROP 0 LASTPIN (-3625 2800) $PN CY6
J 0
(-3615 2810);
DISPLAY 0.489362 (-3615 2810);
PAINT MONO (-3615 2810);
FORCEPROP 0 LASTPIN (-3625 2750) $PN DA7
J 0
(-3615 2760);
DISPLAY 0.489362 (-3615 2760);
PAINT MONO (-3615 2760);
FORCEPROP 0 LASTPIN (-3625 2700) $PN DA5
J 0
(-3615 2710);
DISPLAY 0.489362 (-3615 2710);
PAINT MONO (-3615 2710);
FORCEPROP 0 LASTPIN (-3625 2650) $PN DB7
J 0
(-3615 2660);
DISPLAY 0.489362 (-3615 2660);
PAINT MONO (-3615 2660);
FORCEPROP 0 LASTPIN (-3625 2600) $PN DD6
J 0
(-3615 2610);
DISPLAY 0.489362 (-3615 2610);
PAINT MONO (-3615 2610);
FORCEPROP 0 LASTPIN (-3625 2550) $PN DE7
J 0
(-3615 2560);
DISPLAY 0.489362 (-3615 2560);
PAINT MONO (-3615 2560);
FORCEPROP 0 LASTPIN (-3625 2500) $PN DE5
J 0
(-3615 2510);
DISPLAY 0.489362 (-3615 2510);
PAINT MONO (-3615 2510);
FORCEPROP 0 LASTPIN (-3625 2450) $PN DF7
J 0
(-3615 2460);
DISPLAY 0.489362 (-3615 2460);
PAINT MONO (-3615 2460);
FORCEPROP 0 LASTPIN (-5225 4900) $PN CD6
J 2
(-5235 4910);
DISPLAY 0.489362 (-5235 4910);
PAINT MONO (-5235 4910);
FORCEPROP 0 LASTPIN (-5225 4800) $PN CK6
J 2
(-5235 4810);
DISPLAY 0.489362 (-5235 4810);
PAINT MONO (-5235 4810);
FORCEPROP 0 LASTPIN (-5225 4700) $PN CT6
J 2
(-5235 4710);
DISPLAY 0.489362 (-5235 4710);
PAINT MONO (-5235 4710);
FORCEPROP 0 LASTPIN (-5225 4600) $PN DB6
J 2
(-5235 4610);
DISPLAY 0.489362 (-5235 4610);
PAINT MONO (-5235 4610);
FORCEPROP 0 LASTPIN (-5225 4500) $PN BY7
J 2
(-5235 4510);
DISPLAY 0.489362 (-5235 4510);
PAINT MONO (-5235 4510);
FORCEPROP 0 LASTPIN (-5225 4400) $PN CF7
J 2
(-5235 4410);
DISPLAY 0.489362 (-5235 4410);
PAINT MONO (-5235 4410);
FORCEPROP 0 LASTPIN (-5225 4300) $PN CM7
J 2
(-5235 4310);
DISPLAY 0.489362 (-5235 4310);
PAINT MONO (-5235 4310);
FORCEPROP 0 LASTPIN (-5225 4200) $PN CV7
J 2
(-5235 4210);
DISPLAY 0.489362 (-5235 4210);
PAINT MONO (-5235 4210);
FORCEPROP 0 LASTPIN (-5225 4100) $PN DD7
J 2
(-5235 4110);
DISPLAY 0.489362 (-5235 4110);
PAINT MONO (-5235 4110);
FORCEPROP 0 LASTPIN (-5225 4000) $PN BV6
J 2
(-5235 4010);
DISPLAY 0.489362 (-5235 4010);
PAINT MONO (-5235 4010);
FORCEPROP 0 LASTPIN (-5225 4850) $PN CE5
J 2
(-5235 4860);
DISPLAY 0.489362 (-5235 4860);
PAINT MONO (-5235 4860);
FORCEPROP 0 LASTPIN (-5225 4750) $PN CL5
J 2
(-5235 4760);
DISPLAY 0.489362 (-5235 4760);
PAINT MONO (-5235 4760);
FORCEPROP 0 LASTPIN (-5225 4650) $PN CU5
J 2
(-5235 4660);
DISPLAY 0.489362 (-5235 4660);
PAINT MONO (-5235 4660);
FORCEPROP 0 LASTPIN (-5225 4550) $PN DC5
J 2
(-5235 4560);
DISPLAY 0.489362 (-5235 4560);
PAINT MONO (-5235 4560);
FORCEPROP 0 LASTPIN (-5225 4450) $PN BW7
J 2
(-5235 4460);
DISPLAY 0.489362 (-5235 4460);
PAINT MONO (-5235 4460);
FORCEPROP 0 LASTPIN (-5225 4350) $PN CE7
J 2
(-5235 4360);
DISPLAY 0.489362 (-5235 4360);
PAINT MONO (-5235 4360);
FORCEPROP 0 LASTPIN (-5225 4250) $PN CL7
J 2
(-5235 4260);
DISPLAY 0.489362 (-5235 4260);
PAINT MONO (-5235 4260);
FORCEPROP 0 LASTPIN (-5225 4150) $PN CU7
J 2
(-5235 4160);
DISPLAY 0.489362 (-5235 4160);
PAINT MONO (-5235 4160);
FORCEPROP 0 LASTPIN (-5225 4050) $PN DC7
J 2
(-5235 4060);
DISPLAY 0.489362 (-5235 4060);
PAINT MONO (-5235 4060);
FORCEPROP 0 LASTPIN (-5225 3950) $PN BW5
J 2
(-5235 3960);
DISPLAY 0.489362 (-5235 3960);
PAINT MONO (-5235 3960);
FORCEPROP 0 LASTPIN (-5225 2200) $PN BL7
J 2
(-5235 2210);
DISPLAY 0.489362 (-5235 2210);
PAINT MONO (-5235 2210);
FORCEPROP 0 LASTPIN (-5225 1150) $PN BF7
J 2
(-5235 1160);
DISPLAY 0.489362 (-5235 1160);
PAINT MONO (-5235 1160);
FORCEPROP 2 LAST PART_TYPE SMLF
J 0
(-5050 6500);
DISPLAY 1.021277 (-5050 6500);
FORCEPROP 1 LAST MATERIAL IO
J 0
(-5070 6132);
DISPLAY 0.489362 (-5070 6132);
PAINT SKYBLUE (-5070 6132);
FORCEPROP 2 LAST VALUE SOCKET6096_13568-001
J 0
(-5050 6450);
DISPLAY 0.489362 (-5050 6450);
PAINT SKYBLUE (-5050 6450);
FORCEPROP 1 LAST NEEDS_NO_SIZE TRUE
J 0
(-4425 3575);
DISPLAY 0.723404 (-4425 3575);
PAINT GREEN (-4425 3575);
DISPLAY INVISIBLE (-4425 3575);
FORCEPROP 1 LAST CDS_LMAN_SYM_OUTLINE -650,2525,650,-2525
J 0
(-4425 3575);
DISPLAY 0.468085 (-4425 3575);
PAINT GREEN (-4425 3575);
DISPLAY INVISIBLE (-4425 3575);
FORCEPROP 2 LAST CDS_LIB pure_quanta
J 0
(-4425 3575);
DISPLAY INVISIBLE (-4425 3575);
FORCEPROP 1 LAST PATH I159
J 0
(-4425 3575);
DISPLAY 0.723404 (-4425 3575);
PAINT GREEN (-4425 3575);
DISPLAY INVISIBLE (-4425 3575);
FORCEPROP 1 LAST PART_NUMBER DGA^6000030
J 0
(-5070 6259);
DISPLAY 0.489362 (-5070 6259);
PAINT SKYBLUE (-5070 6259);
DISPLAY INVISIBLE (-5070 6259);
FORCEADD OFFPAGE..3
(-2425 5975);
FORCEPROP 2 LAST $XR0 96 
J 0
(-2211 5975);
DISPLAY 0.638298 (-2211 5975);
PAINT MONO (-2211 5975);
FORCEPROP 2 LAST CDS_LIB mstr_standard
J 0
(-2425 5975);
DISPLAY 0.723404 (-2425 5975);
PAINT MONO (-2425 5975);
DISPLAY INVISIBLE (-2425 5975);
FORCEPROP 1 LAST OFFPAGE TRUE
J 0
(-2100 5850);
DISPLAY 0.872340 (-2100 5850);
PAINT GREEN (-2100 5850);
DISPLAY INVISIBLE (-2100 5850);
FORCEPROP 1 LAST COMMENT_BODY TRUE
J 0
(-2475 5875);
DISPLAY 0.872340 (-2475 5875);
PAINT GREEN (-2475 5875);
DISPLAY INVISIBLE (-2475 5875);
FORCEPROP 2 LAST PATH I160
J 0
(-2200 6025);
DISPLAY 1.021277 (-2200 6025);
DISPLAY INVISIBLE (-2200 6025);
FORCEADD OFFPAGE..3
(-2425 4175);
FORCEPROP 2 LAST $XR0 96 
J 0
(-2211 4175);
DISPLAY 0.638298 (-2211 4175);
PAINT MONO (-2211 4175);
FORCEPROP 2 LAST CDS_LIB mstr_standard
J 0
(-2425 4175);
DISPLAY 0.723404 (-2425 4175);
PAINT MONO (-2425 4175);
DISPLAY INVISIBLE (-2425 4175);
FORCEPROP 1 LAST OFFPAGE TRUE
J 0
(-2100 4050);
DISPLAY 0.872340 (-2100 4050);
PAINT GREEN (-2100 4050);
DISPLAY INVISIBLE (-2100 4050);
FORCEPROP 1 LAST COMMENT_BODY TRUE
J 0
(-2475 4075);
DISPLAY 0.872340 (-2475 4075);
PAINT GREEN (-2475 4075);
DISPLAY INVISIBLE (-2475 4075);
FORCEPROP 2 LAST PATH I161
J 0
(-2200 4225);
DISPLAY 1.021277 (-2200 4225);
DISPLAY INVISIBLE (-2200 4225);
FORCEADD TAP..1
(-3150 5950);
FORCEPROP 3 LASTPIN (-3200 5950) SIG_NAME M_K_CPU0_SA_DQ<0>
J 0
(-3190 5960);
DISPLAY 0.659574 (-3190 5960);
PAINT MONO (-3190 5960);
DISPLAY INVISIBLE (-3190 5960);
FORCEPROP 1 LASTPIN (-3200 5950) BN 0
J 0
(-3212 5958);
DISPLAY 0.489362 (-3212 5958);
PAINT GREEN (-3212 5958);
FORCEPROP 2 LAST CDS_LIB mstr_standard
J 0
(-3150 5950);
DISPLAY 0.723404 (-3150 5950);
PAINT MONO (-3150 5950);
DISPLAY INVISIBLE (-3150 5950);
FORCEPROP 1 LAST BODY_TYPE PLUMBING
J 0
(-3150 6000);
DISPLAY 0.872340 (-3150 6000);
PAINT GREEN (-3150 6000);
DISPLAY INVISIBLE (-3150 6000);
FORCEPROP 1 LAST HDL_TAP TRUE
J 0
(-2825 5825);
DISPLAY 0.872340 (-2825 5825);
DISPLAY INVISIBLE (-2825 5825);
FORCEPROP 1 LAST PATH I162
J 0
(-3152 5950);
DISPLAY 0.872340 (-3152 5950);
PAINT GREEN (-3152 5950);
DISPLAY INVISIBLE (-3152 5950);
FORCEADD TAP..1
(-3150 5900);
FORCEPROP 3 LASTPIN (-3200 5900) SIG_NAME M_K_CPU0_SA_DQ<1>
J 0
(-3190 5910);
DISPLAY 0.659574 (-3190 5910);
PAINT MONO (-3190 5910);
DISPLAY INVISIBLE (-3190 5910);
FORCEPROP 1 LASTPIN (-3200 5900) BN 1
J 0
(-3212 5908);
DISPLAY 0.489362 (-3212 5908);
PAINT GREEN (-3212 5908);
FORCEPROP 2 LAST CDS_LIB mstr_standard
J 0
(-3150 5900);
DISPLAY 0.723404 (-3150 5900);
PAINT MONO (-3150 5900);
DISPLAY INVISIBLE (-3150 5900);
FORCEPROP 1 LAST BODY_TYPE PLUMBING
J 0
(-3150 5950);
DISPLAY 0.872340 (-3150 5950);
PAINT GREEN (-3150 5950);
DISPLAY INVISIBLE (-3150 5950);
FORCEPROP 1 LAST HDL_TAP TRUE
J 0
(-2825 5775);
DISPLAY 0.872340 (-2825 5775);
DISPLAY INVISIBLE (-2825 5775);
FORCEPROP 1 LAST PATH I163
J 0
(-3152 5900);
DISPLAY 0.872340 (-3152 5900);
PAINT GREEN (-3152 5900);
DISPLAY INVISIBLE (-3152 5900);
FORCEADD TAP..1
(-3150 5850);
FORCEPROP 3 LASTPIN (-3200 5850) SIG_NAME M_K_CPU0_SA_DQ<2>
J 0
(-3190 5860);
DISPLAY 0.659574 (-3190 5860);
PAINT MONO (-3190 5860);
DISPLAY INVISIBLE (-3190 5860);
FORCEPROP 1 LASTPIN (-3200 5850) BN 2
J 0
(-3212 5858);
DISPLAY 0.489362 (-3212 5858);
PAINT GREEN (-3212 5858);
FORCEPROP 2 LAST CDS_LIB mstr_standard
J 0
(-3150 5850);
DISPLAY 0.723404 (-3150 5850);
PAINT MONO (-3150 5850);
DISPLAY INVISIBLE (-3150 5850);
FORCEPROP 1 LAST BODY_TYPE PLUMBING
J 0
(-3150 5900);
DISPLAY 0.872340 (-3150 5900);
PAINT GREEN (-3150 5900);
DISPLAY INVISIBLE (-3150 5900);
FORCEPROP 1 LAST HDL_TAP TRUE
J 0
(-2825 5725);
DISPLAY 0.872340 (-2825 5725);
DISPLAY INVISIBLE (-2825 5725);
FORCEPROP 1 LAST PATH I164
J 0
(-3152 5850);
DISPLAY 0.872340 (-3152 5850);
PAINT GREEN (-3152 5850);
DISPLAY INVISIBLE (-3152 5850);
FORCEADD TAP..1
(-3150 5800);
FORCEPROP 3 LASTPIN (-3200 5800) SIG_NAME M_K_CPU0_SA_DQ<3>
J 0
(-3190 5810);
DISPLAY 0.659574 (-3190 5810);
PAINT MONO (-3190 5810);
DISPLAY INVISIBLE (-3190 5810);
FORCEPROP 1 LASTPIN (-3200 5800) BN 3
J 0
(-3212 5808);
DISPLAY 0.489362 (-3212 5808);
PAINT GREEN (-3212 5808);
FORCEPROP 2 LAST CDS_LIB mstr_standard
J 0
(-3150 5800);
DISPLAY 0.723404 (-3150 5800);
PAINT MONO (-3150 5800);
DISPLAY INVISIBLE (-3150 5800);
FORCEPROP 1 LAST BODY_TYPE PLUMBING
J 0
(-3150 5850);
DISPLAY 0.872340 (-3150 5850);
PAINT GREEN (-3150 5850);
DISPLAY INVISIBLE (-3150 5850);
FORCEPROP 1 LAST HDL_TAP TRUE
J 0
(-2825 5675);
DISPLAY 0.872340 (-2825 5675);
DISPLAY INVISIBLE (-2825 5675);
FORCEPROP 1 LAST PATH I165
J 0
(-3152 5800);
DISPLAY 0.872340 (-3152 5800);
PAINT GREEN (-3152 5800);
DISPLAY INVISIBLE (-3152 5800);
FORCEADD TAP..1
(-3150 5700);
FORCEPROP 3 LASTPIN (-3200 5700) SIG_NAME M_K_CPU0_SA_DQ<5>
J 0
(-3190 5710);
DISPLAY 0.659574 (-3190 5710);
PAINT MONO (-3190 5710);
DISPLAY INVISIBLE (-3190 5710);
FORCEPROP 1 LASTPIN (-3200 5700) BN 5
J 0
(-3212 5708);
DISPLAY 0.489362 (-3212 5708);
PAINT GREEN (-3212 5708);
FORCEPROP 2 LAST CDS_LIB mstr_standard
J 0
(-3150 5700);
DISPLAY 0.723404 (-3150 5700);
PAINT MONO (-3150 5700);
DISPLAY INVISIBLE (-3150 5700);
FORCEPROP 1 LAST BODY_TYPE PLUMBING
J 0
(-3150 5750);
DISPLAY 0.872340 (-3150 5750);
PAINT GREEN (-3150 5750);
DISPLAY INVISIBLE (-3150 5750);
FORCEPROP 1 LAST HDL_TAP TRUE
J 0
(-2825 5575);
DISPLAY 0.872340 (-2825 5575);
DISPLAY INVISIBLE (-2825 5575);
FORCEPROP 1 LAST PATH I166
J 0
(-3152 5700);
DISPLAY 0.872340 (-3152 5700);
PAINT GREEN (-3152 5700);
DISPLAY INVISIBLE (-3152 5700);
FORCEADD TAP..1
(-3150 5650);
FORCEPROP 3 LASTPIN (-3200 5650) SIG_NAME M_K_CPU0_SA_DQ<6>
J 0
(-3190 5660);
DISPLAY 0.659574 (-3190 5660);
PAINT MONO (-3190 5660);
DISPLAY INVISIBLE (-3190 5660);
FORCEPROP 1 LASTPIN (-3200 5650) BN 6
J 0
(-3212 5658);
DISPLAY 0.489362 (-3212 5658);
PAINT GREEN (-3212 5658);
FORCEPROP 2 LAST CDS_LIB mstr_standard
J 0
(-3150 5650);
DISPLAY 0.723404 (-3150 5650);
PAINT MONO (-3150 5650);
DISPLAY INVISIBLE (-3150 5650);
FORCEPROP 1 LAST BODY_TYPE PLUMBING
J 0
(-3150 5700);
DISPLAY 0.872340 (-3150 5700);
PAINT GREEN (-3150 5700);
DISPLAY INVISIBLE (-3150 5700);
FORCEPROP 1 LAST HDL_TAP TRUE
J 0
(-2825 5525);
DISPLAY 0.872340 (-2825 5525);
DISPLAY INVISIBLE (-2825 5525);
FORCEPROP 1 LAST PATH I167
J 0
(-3152 5650);
DISPLAY 0.872340 (-3152 5650);
PAINT GREEN (-3152 5650);
DISPLAY INVISIBLE (-3152 5650);
FORCEADD TAP..1
(-3150 5750);
FORCEPROP 3 LASTPIN (-3200 5750) SIG_NAME M_K_CPU0_SA_DQ<4>
J 0
(-3190 5760);
DISPLAY 0.659574 (-3190 5760);
PAINT MONO (-3190 5760);
DISPLAY INVISIBLE (-3190 5760);
FORCEPROP 1 LASTPIN (-3200 5750) BN 4
J 0
(-3212 5758);
DISPLAY 0.489362 (-3212 5758);
PAINT GREEN (-3212 5758);
FORCEPROP 2 LAST CDS_LIB mstr_standard
J 0
(-3150 5750);
DISPLAY 0.723404 (-3150 5750);
PAINT MONO (-3150 5750);
DISPLAY INVISIBLE (-3150 5750);
FORCEPROP 1 LAST BODY_TYPE PLUMBING
J 0
(-3150 5800);
DISPLAY 0.872340 (-3150 5800);
PAINT GREEN (-3150 5800);
DISPLAY INVISIBLE (-3150 5800);
FORCEPROP 1 LAST HDL_TAP TRUE
J 0
(-2825 5625);
DISPLAY 0.872340 (-2825 5625);
DISPLAY INVISIBLE (-2825 5625);
FORCEPROP 1 LAST PATH I168
J 0
(-3152 5750);
DISPLAY 0.872340 (-3152 5750);
PAINT GREEN (-3152 5750);
DISPLAY INVISIBLE (-3152 5750);
FORCEADD TAP..1
(-3150 5600);
FORCEPROP 3 LASTPIN (-3200 5600) SIG_NAME M_K_CPU0_SA_DQ<7>
J 0
(-3190 5610);
DISPLAY 0.659574 (-3190 5610);
PAINT MONO (-3190 5610);
DISPLAY INVISIBLE (-3190 5610);
FORCEPROP 1 LASTPIN (-3200 5600) BN 7
J 0
(-3212 5608);
DISPLAY 0.489362 (-3212 5608);
PAINT GREEN (-3212 5608);
FORCEPROP 2 LAST CDS_LIB mstr_standard
J 0
(-3150 5600);
DISPLAY 0.723404 (-3150 5600);
PAINT MONO (-3150 5600);
DISPLAY INVISIBLE (-3150 5600);
FORCEPROP 1 LAST BODY_TYPE PLUMBING
J 0
(-3150 5650);
DISPLAY 0.872340 (-3150 5650);
PAINT GREEN (-3150 5650);
DISPLAY INVISIBLE (-3150 5650);
FORCEPROP 1 LAST HDL_TAP TRUE
J 0
(-2825 5475);
DISPLAY 0.872340 (-2825 5475);
DISPLAY INVISIBLE (-2825 5475);
FORCEPROP 1 LAST PATH I169
J 0
(-3152 5600);
DISPLAY 0.872340 (-3152 5600);
PAINT GREEN (-3152 5600);
DISPLAY INVISIBLE (-3152 5600);
FORCEADD TAP..1
(-3150 5400);
FORCEPROP 3 LASTPIN (-3200 5400) SIG_NAME M_K_CPU0_SA_DQ<10>
J 0
(-3190 5410);
DISPLAY 0.659574 (-3190 5410);
PAINT MONO (-3190 5410);
DISPLAY INVISIBLE (-3190 5410);
FORCEPROP 1 LASTPIN (-3200 5400) BN 10
J 0
(-3212 5408);
DISPLAY 0.489362 (-3212 5408);
PAINT GREEN (-3212 5408);
FORCEPROP 2 LAST CDS_LIB mstr_standard
J 0
(-3150 5400);
DISPLAY 0.723404 (-3150 5400);
PAINT MONO (-3150 5400);
DISPLAY INVISIBLE (-3150 5400);
FORCEPROP 1 LAST BODY_TYPE PLUMBING
J 0
(-3150 5450);
DISPLAY 0.872340 (-3150 5450);
PAINT GREEN (-3150 5450);
DISPLAY INVISIBLE (-3150 5450);
FORCEPROP 1 LAST HDL_TAP TRUE
J 0
(-2825 5275);
DISPLAY 0.872340 (-2825 5275);
DISPLAY INVISIBLE (-2825 5275);
FORCEPROP 1 LAST PATH I170
J 0
(-3152 5400);
DISPLAY 0.872340 (-3152 5400);
PAINT GREEN (-3152 5400);
DISPLAY INVISIBLE (-3152 5400);
FORCEADD TAP..1
(-3150 5450);
FORCEPROP 3 LASTPIN (-3200 5450) SIG_NAME M_K_CPU0_SA_DQ<9>
J 0
(-3190 5460);
DISPLAY 0.659574 (-3190 5460);
PAINT MONO (-3190 5460);
DISPLAY INVISIBLE (-3190 5460);
FORCEPROP 1 LASTPIN (-3200 5450) BN 9
J 0
(-3212 5458);
DISPLAY 0.489362 (-3212 5458);
PAINT GREEN (-3212 5458);
FORCEPROP 2 LAST CDS_LIB mstr_standard
J 0
(-3150 5450);
DISPLAY 0.723404 (-3150 5450);
PAINT MONO (-3150 5450);
DISPLAY INVISIBLE (-3150 5450);
FORCEPROP 1 LAST BODY_TYPE PLUMBING
J 0
(-3150 5500);
DISPLAY 0.872340 (-3150 5500);
PAINT GREEN (-3150 5500);
DISPLAY INVISIBLE (-3150 5500);
FORCEPROP 1 LAST HDL_TAP TRUE
J 0
(-2825 5325);
DISPLAY 0.872340 (-2825 5325);
DISPLAY INVISIBLE (-2825 5325);
FORCEPROP 1 LAST PATH I171
J 0
(-3152 5450);
DISPLAY 0.872340 (-3152 5450);
PAINT GREEN (-3152 5450);
DISPLAY INVISIBLE (-3152 5450);
FORCEADD TAP..1
(-3150 5500);
FORCEPROP 3 LASTPIN (-3200 5500) SIG_NAME M_K_CPU0_SA_DQ<8>
J 0
(-3190 5510);
DISPLAY 0.659574 (-3190 5510);
PAINT MONO (-3190 5510);
DISPLAY INVISIBLE (-3190 5510);
FORCEPROP 1 LASTPIN (-3200 5500) BN 8
J 0
(-3212 5508);
DISPLAY 0.489362 (-3212 5508);
PAINT GREEN (-3212 5508);
FORCEPROP 2 LAST CDS_LIB mstr_standard
J 0
(-3150 5500);
DISPLAY 0.723404 (-3150 5500);
PAINT MONO (-3150 5500);
DISPLAY INVISIBLE (-3150 5500);
FORCEPROP 1 LAST BODY_TYPE PLUMBING
J 0
(-3150 5550);
DISPLAY 0.872340 (-3150 5550);
PAINT GREEN (-3150 5550);
DISPLAY INVISIBLE (-3150 5550);
FORCEPROP 1 LAST HDL_TAP TRUE
J 0
(-2825 5375);
DISPLAY 0.872340 (-2825 5375);
DISPLAY INVISIBLE (-2825 5375);
FORCEPROP 1 LAST PATH I172
J 0
(-3152 5500);
DISPLAY 0.872340 (-3152 5500);
PAINT GREEN (-3152 5500);
DISPLAY INVISIBLE (-3152 5500);
FORCEADD TAP..1
(-3150 5250);
FORCEPROP 3 LASTPIN (-3200 5250) SIG_NAME M_K_CPU0_SA_DQ<13>
J 0
(-3190 5260);
DISPLAY 0.659574 (-3190 5260);
PAINT MONO (-3190 5260);
DISPLAY INVISIBLE (-3190 5260);
FORCEPROP 1 LASTPIN (-3200 5250) BN 13
J 0
(-3212 5258);
DISPLAY 0.489362 (-3212 5258);
PAINT GREEN (-3212 5258);
FORCEPROP 2 LAST CDS_LIB mstr_standard
J 0
(-3150 5250);
DISPLAY 0.723404 (-3150 5250);
PAINT MONO (-3150 5250);
DISPLAY INVISIBLE (-3150 5250);
FORCEPROP 1 LAST BODY_TYPE PLUMBING
J 0
(-3150 5300);
DISPLAY 0.872340 (-3150 5300);
PAINT GREEN (-3150 5300);
DISPLAY INVISIBLE (-3150 5300);
FORCEPROP 1 LAST HDL_TAP TRUE
J 0
(-2825 5125);
DISPLAY 0.872340 (-2825 5125);
DISPLAY INVISIBLE (-2825 5125);
FORCEPROP 1 LAST PATH I173
J 0
(-3152 5250);
DISPLAY 0.872340 (-3152 5250);
PAINT GREEN (-3152 5250);
DISPLAY INVISIBLE (-3152 5250);
FORCEADD TAP..1
(-3150 5350);
FORCEPROP 3 LASTPIN (-3200 5350) SIG_NAME M_K_CPU0_SA_DQ<11>
J 0
(-3190 5360);
DISPLAY 0.659574 (-3190 5360);
PAINT MONO (-3190 5360);
DISPLAY INVISIBLE (-3190 5360);
FORCEPROP 1 LASTPIN (-3200 5350) BN 11
J 0
(-3212 5358);
DISPLAY 0.489362 (-3212 5358);
PAINT GREEN (-3212 5358);
FORCEPROP 2 LAST CDS_LIB mstr_standard
J 0
(-3150 5350);
DISPLAY 0.723404 (-3150 5350);
PAINT MONO (-3150 5350);
DISPLAY INVISIBLE (-3150 5350);
FORCEPROP 1 LAST BODY_TYPE PLUMBING
J 0
(-3150 5400);
DISPLAY 0.872340 (-3150 5400);
PAINT GREEN (-3150 5400);
DISPLAY INVISIBLE (-3150 5400);
FORCEPROP 1 LAST HDL_TAP TRUE
J 0
(-2825 5225);
DISPLAY 0.872340 (-2825 5225);
DISPLAY INVISIBLE (-2825 5225);
FORCEPROP 1 LAST PATH I174
J 0
(-3152 5350);
DISPLAY 0.872340 (-3152 5350);
PAINT GREEN (-3152 5350);
DISPLAY INVISIBLE (-3152 5350);
FORCEADD TAP..1
(-3150 5300);
FORCEPROP 3 LASTPIN (-3200 5300) SIG_NAME M_K_CPU0_SA_DQ<12>
J 0
(-3190 5310);
DISPLAY 0.659574 (-3190 5310);
PAINT MONO (-3190 5310);
DISPLAY INVISIBLE (-3190 5310);
FORCEPROP 1 LASTPIN (-3200 5300) BN 12
J 0
(-3212 5308);
DISPLAY 0.489362 (-3212 5308);
PAINT GREEN (-3212 5308);
FORCEPROP 2 LAST CDS_LIB mstr_standard
J 0
(-3150 5300);
DISPLAY 0.723404 (-3150 5300);
PAINT MONO (-3150 5300);
DISPLAY INVISIBLE (-3150 5300);
FORCEPROP 1 LAST BODY_TYPE PLUMBING
J 0
(-3150 5350);
DISPLAY 0.872340 (-3150 5350);
PAINT GREEN (-3150 5350);
DISPLAY INVISIBLE (-3150 5350);
FORCEPROP 1 LAST HDL_TAP TRUE
J 0
(-2825 5175);
DISPLAY 0.872340 (-2825 5175);
DISPLAY INVISIBLE (-2825 5175);
FORCEPROP 1 LAST PATH I175
J 0
(-3152 5300);
DISPLAY 0.872340 (-3152 5300);
PAINT GREEN (-3152 5300);
DISPLAY INVISIBLE (-3152 5300);
FORCEADD TAP..1
(-3150 5150);
FORCEPROP 3 LASTPIN (-3200 5150) SIG_NAME M_K_CPU0_SA_DQ<15>
J 0
(-3190 5160);
DISPLAY 0.659574 (-3190 5160);
PAINT MONO (-3190 5160);
DISPLAY INVISIBLE (-3190 5160);
FORCEPROP 1 LASTPIN (-3200 5150) BN 15
J 0
(-3212 5158);
DISPLAY 0.489362 (-3212 5158);
PAINT GREEN (-3212 5158);
FORCEPROP 2 LAST CDS_LIB mstr_standard
J 0
(-3150 5150);
DISPLAY 0.723404 (-3150 5150);
PAINT MONO (-3150 5150);
DISPLAY INVISIBLE (-3150 5150);
FORCEPROP 1 LAST BODY_TYPE PLUMBING
J 0
(-3150 5200);
DISPLAY 0.872340 (-3150 5200);
PAINT GREEN (-3150 5200);
DISPLAY INVISIBLE (-3150 5200);
FORCEPROP 1 LAST HDL_TAP TRUE
J 0
(-2825 5025);
DISPLAY 0.872340 (-2825 5025);
DISPLAY INVISIBLE (-2825 5025);
FORCEPROP 1 LAST PATH I176
J 0
(-3152 5150);
DISPLAY 0.872340 (-3152 5150);
PAINT GREEN (-3152 5150);
DISPLAY INVISIBLE (-3152 5150);
FORCEADD TAP..1
(-3150 5200);
FORCEPROP 3 LASTPIN (-3200 5200) SIG_NAME M_K_CPU0_SA_DQ<14>
J 0
(-3190 5210);
DISPLAY 0.659574 (-3190 5210);
PAINT MONO (-3190 5210);
DISPLAY INVISIBLE (-3190 5210);
FORCEPROP 1 LASTPIN (-3200 5200) BN 14
J 0
(-3212 5208);
DISPLAY 0.489362 (-3212 5208);
PAINT GREEN (-3212 5208);
FORCEPROP 2 LAST CDS_LIB mstr_standard
J 0
(-3150 5200);
DISPLAY 0.723404 (-3150 5200);
PAINT MONO (-3150 5200);
DISPLAY INVISIBLE (-3150 5200);
FORCEPROP 1 LAST BODY_TYPE PLUMBING
J 0
(-3150 5250);
DISPLAY 0.872340 (-3150 5250);
PAINT GREEN (-3150 5250);
DISPLAY INVISIBLE (-3150 5250);
FORCEPROP 1 LAST HDL_TAP TRUE
J 0
(-2825 5075);
DISPLAY 0.872340 (-2825 5075);
DISPLAY INVISIBLE (-2825 5075);
FORCEPROP 1 LAST PATH I177
J 0
(-3152 5200);
DISPLAY 0.872340 (-3152 5200);
PAINT GREEN (-3152 5200);
DISPLAY INVISIBLE (-3152 5200);
FORCEADD TAP..1
(-3150 5000);
FORCEPROP 3 LASTPIN (-3200 5000) SIG_NAME M_K_CPU0_SA_DQ<17>
J 0
(-3190 5010);
DISPLAY 0.659574 (-3190 5010);
PAINT MONO (-3190 5010);
DISPLAY INVISIBLE (-3190 5010);
FORCEPROP 1 LASTPIN (-3200 5000) BN 17
J 0
(-3212 5008);
DISPLAY 0.489362 (-3212 5008);
PAINT GREEN (-3212 5008);
FORCEPROP 2 LAST CDS_LIB mstr_standard
J 0
(-3150 5000);
DISPLAY 0.723404 (-3150 5000);
PAINT MONO (-3150 5000);
DISPLAY INVISIBLE (-3150 5000);
FORCEPROP 1 LAST BODY_TYPE PLUMBING
J 0
(-3150 5050);
DISPLAY 0.872340 (-3150 5050);
PAINT GREEN (-3150 5050);
DISPLAY INVISIBLE (-3150 5050);
FORCEPROP 1 LAST HDL_TAP TRUE
J 0
(-2825 4875);
DISPLAY 0.872340 (-2825 4875);
DISPLAY INVISIBLE (-2825 4875);
FORCEPROP 1 LAST PATH I178
J 0
(-3152 5000);
DISPLAY 0.872340 (-3152 5000);
PAINT GREEN (-3152 5000);
DISPLAY INVISIBLE (-3152 5000);
FORCEADD TAP..1
(-3150 5050);
FORCEPROP 3 LASTPIN (-3200 5050) SIG_NAME M_K_CPU0_SA_DQ<16>
J 0
(-3190 5060);
DISPLAY 0.659574 (-3190 5060);
PAINT MONO (-3190 5060);
DISPLAY INVISIBLE (-3190 5060);
FORCEPROP 1 LASTPIN (-3200 5050) BN 16
J 0
(-3212 5058);
DISPLAY 0.489362 (-3212 5058);
PAINT GREEN (-3212 5058);
FORCEPROP 2 LAST CDS_LIB mstr_standard
J 0
(-3150 5050);
DISPLAY 0.723404 (-3150 5050);
PAINT MONO (-3150 5050);
DISPLAY INVISIBLE (-3150 5050);
FORCEPROP 1 LAST BODY_TYPE PLUMBING
J 0
(-3150 5100);
DISPLAY 0.872340 (-3150 5100);
PAINT GREEN (-3150 5100);
DISPLAY INVISIBLE (-3150 5100);
FORCEPROP 1 LAST HDL_TAP TRUE
J 0
(-2825 4925);
DISPLAY 0.872340 (-2825 4925);
DISPLAY INVISIBLE (-2825 4925);
FORCEPROP 1 LAST PATH I179
J 0
(-3152 5050);
DISPLAY 0.872340 (-3152 5050);
PAINT GREEN (-3152 5050);
DISPLAY INVISIBLE (-3152 5050);
FORCEADD TAP..1
(-3150 4900);
FORCEPROP 3 LASTPIN (-3200 4900) SIG_NAME M_K_CPU0_SA_DQ<19>
J 0
(-3190 4910);
DISPLAY 0.659574 (-3190 4910);
PAINT MONO (-3190 4910);
DISPLAY INVISIBLE (-3190 4910);
FORCEPROP 1 LASTPIN (-3200 4900) BN 19
J 0
(-3212 4908);
DISPLAY 0.489362 (-3212 4908);
PAINT GREEN (-3212 4908);
FORCEPROP 2 LAST CDS_LIB mstr_standard
J 0
(-3150 4900);
DISPLAY 0.723404 (-3150 4900);
PAINT MONO (-3150 4900);
DISPLAY INVISIBLE (-3150 4900);
FORCEPROP 1 LAST BODY_TYPE PLUMBING
J 0
(-3150 4950);
DISPLAY 0.872340 (-3150 4950);
PAINT GREEN (-3150 4950);
DISPLAY INVISIBLE (-3150 4950);
FORCEPROP 1 LAST HDL_TAP TRUE
J 0
(-2825 4775);
DISPLAY 0.872340 (-2825 4775);
DISPLAY INVISIBLE (-2825 4775);
FORCEPROP 1 LAST PATH I180
J 0
(-3152 4900);
DISPLAY 0.872340 (-3152 4900);
PAINT GREEN (-3152 4900);
DISPLAY INVISIBLE (-3152 4900);
FORCEADD TAP..1
(-3150 4950);
FORCEPROP 3 LASTPIN (-3200 4950) SIG_NAME M_K_CPU0_SA_DQ<18>
J 0
(-3190 4960);
DISPLAY 0.659574 (-3190 4960);
PAINT MONO (-3190 4960);
DISPLAY INVISIBLE (-3190 4960);
FORCEPROP 1 LASTPIN (-3200 4950) BN 18
J 0
(-3212 4958);
DISPLAY 0.489362 (-3212 4958);
PAINT GREEN (-3212 4958);
FORCEPROP 2 LAST CDS_LIB mstr_standard
J 0
(-3150 4950);
DISPLAY 0.723404 (-3150 4950);
PAINT MONO (-3150 4950);
DISPLAY INVISIBLE (-3150 4950);
FORCEPROP 1 LAST BODY_TYPE PLUMBING
J 0
(-3150 5000);
DISPLAY 0.872340 (-3150 5000);
PAINT GREEN (-3150 5000);
DISPLAY INVISIBLE (-3150 5000);
FORCEPROP 1 LAST HDL_TAP TRUE
J 0
(-2825 4825);
DISPLAY 0.872340 (-2825 4825);
DISPLAY INVISIBLE (-2825 4825);
FORCEPROP 1 LAST PATH I181
J 0
(-3152 4950);
DISPLAY 0.872340 (-3152 4950);
PAINT GREEN (-3152 4950);
DISPLAY INVISIBLE (-3152 4950);
FORCEADD TAP..1
(-3150 4850);
FORCEPROP 3 LASTPIN (-3200 4850) SIG_NAME M_K_CPU0_SA_DQ<20>
J 0
(-3190 4860);
DISPLAY 0.659574 (-3190 4860);
PAINT MONO (-3190 4860);
DISPLAY INVISIBLE (-3190 4860);
FORCEPROP 1 LASTPIN (-3200 4850) BN 20
J 0
(-3212 4858);
DISPLAY 0.489362 (-3212 4858);
PAINT GREEN (-3212 4858);
FORCEPROP 2 LAST CDS_LIB mstr_standard
J 0
(-3150 4850);
DISPLAY 0.723404 (-3150 4850);
PAINT MONO (-3150 4850);
DISPLAY INVISIBLE (-3150 4850);
FORCEPROP 1 LAST BODY_TYPE PLUMBING
J 0
(-3150 4900);
DISPLAY 0.872340 (-3150 4900);
PAINT GREEN (-3150 4900);
DISPLAY INVISIBLE (-3150 4900);
FORCEPROP 1 LAST HDL_TAP TRUE
J 0
(-2825 4725);
DISPLAY 0.872340 (-2825 4725);
DISPLAY INVISIBLE (-2825 4725);
FORCEPROP 1 LAST PATH I182
J 0
(-3152 4850);
DISPLAY 0.872340 (-3152 4850);
PAINT GREEN (-3152 4850);
DISPLAY INVISIBLE (-3152 4850);
FORCEADD TAP..1
(-3150 4750);
FORCEPROP 3 LASTPIN (-3200 4750) SIG_NAME M_K_CPU0_SA_DQ<22>
J 0
(-3190 4760);
DISPLAY 0.659574 (-3190 4760);
PAINT MONO (-3190 4760);
DISPLAY INVISIBLE (-3190 4760);
FORCEPROP 1 LASTPIN (-3200 4750) BN 22
J 0
(-3212 4758);
DISPLAY 0.489362 (-3212 4758);
PAINT GREEN (-3212 4758);
FORCEPROP 2 LAST CDS_LIB mstr_standard
J 0
(-3150 4750);
DISPLAY 0.723404 (-3150 4750);
PAINT MONO (-3150 4750);
DISPLAY INVISIBLE (-3150 4750);
FORCEPROP 1 LAST BODY_TYPE PLUMBING
J 0
(-3150 4800);
DISPLAY 0.872340 (-3150 4800);
PAINT GREEN (-3150 4800);
DISPLAY INVISIBLE (-3150 4800);
FORCEPROP 1 LAST HDL_TAP TRUE
J 0
(-2825 4625);
DISPLAY 0.872340 (-2825 4625);
DISPLAY INVISIBLE (-2825 4625);
FORCEPROP 1 LAST PATH I183
J 0
(-3152 4750);
DISPLAY 0.872340 (-3152 4750);
PAINT GREEN (-3152 4750);
DISPLAY INVISIBLE (-3152 4750);
FORCEADD TAP..1
(-3150 4800);
FORCEPROP 3 LASTPIN (-3200 4800) SIG_NAME M_K_CPU0_SA_DQ<21>
J 0
(-3190 4810);
DISPLAY 0.659574 (-3190 4810);
PAINT MONO (-3190 4810);
DISPLAY INVISIBLE (-3190 4810);
FORCEPROP 1 LASTPIN (-3200 4800) BN 21
J 0
(-3212 4808);
DISPLAY 0.489362 (-3212 4808);
PAINT GREEN (-3212 4808);
FORCEPROP 2 LAST CDS_LIB mstr_standard
J 0
(-3150 4800);
DISPLAY 0.723404 (-3150 4800);
PAINT MONO (-3150 4800);
DISPLAY INVISIBLE (-3150 4800);
FORCEPROP 1 LAST BODY_TYPE PLUMBING
J 0
(-3150 4850);
DISPLAY 0.872340 (-3150 4850);
PAINT GREEN (-3150 4850);
DISPLAY INVISIBLE (-3150 4850);
FORCEPROP 1 LAST HDL_TAP TRUE
J 0
(-2825 4675);
DISPLAY 0.872340 (-2825 4675);
DISPLAY INVISIBLE (-2825 4675);
FORCEPROP 1 LAST PATH I184
J 0
(-3152 4800);
DISPLAY 0.872340 (-3152 4800);
PAINT GREEN (-3152 4800);
DISPLAY INVISIBLE (-3152 4800);
FORCEADD TAP..1
(-3150 4700);
FORCEPROP 3 LASTPIN (-3200 4700) SIG_NAME M_K_CPU0_SA_DQ<23>
J 0
(-3190 4710);
DISPLAY 0.659574 (-3190 4710);
PAINT MONO (-3190 4710);
DISPLAY INVISIBLE (-3190 4710);
FORCEPROP 1 LASTPIN (-3200 4700) BN 23
J 0
(-3212 4708);
DISPLAY 0.489362 (-3212 4708);
PAINT GREEN (-3212 4708);
FORCEPROP 2 LAST CDS_LIB mstr_standard
J 0
(-3150 4700);
DISPLAY 0.723404 (-3150 4700);
PAINT MONO (-3150 4700);
DISPLAY INVISIBLE (-3150 4700);
FORCEPROP 1 LAST BODY_TYPE PLUMBING
J 0
(-3150 4750);
DISPLAY 0.872340 (-3150 4750);
PAINT GREEN (-3150 4750);
DISPLAY INVISIBLE (-3150 4750);
FORCEPROP 1 LAST HDL_TAP TRUE
J 0
(-2825 4575);
DISPLAY 0.872340 (-2825 4575);
DISPLAY INVISIBLE (-2825 4575);
FORCEPROP 1 LAST PATH I185
J 0
(-3152 4700);
DISPLAY 0.872340 (-3152 4700);
PAINT GREEN (-3152 4700);
DISPLAY INVISIBLE (-3152 4700);
FORCEADD TAP..1
(-3150 4550);
FORCEPROP 3 LASTPIN (-3200 4550) SIG_NAME M_K_CPU0_SA_DQ<25>
J 0
(-3190 4560);
DISPLAY 0.659574 (-3190 4560);
PAINT MONO (-3190 4560);
DISPLAY INVISIBLE (-3190 4560);
FORCEPROP 1 LASTPIN (-3200 4550) BN 25
J 0
(-3212 4558);
DISPLAY 0.489362 (-3212 4558);
PAINT GREEN (-3212 4558);
FORCEPROP 2 LAST CDS_LIB mstr_standard
J 0
(-3150 4550);
DISPLAY 0.723404 (-3150 4550);
PAINT MONO (-3150 4550);
DISPLAY INVISIBLE (-3150 4550);
FORCEPROP 1 LAST BODY_TYPE PLUMBING
J 0
(-3150 4600);
DISPLAY 0.872340 (-3150 4600);
PAINT GREEN (-3150 4600);
DISPLAY INVISIBLE (-3150 4600);
FORCEPROP 1 LAST HDL_TAP TRUE
J 0
(-2825 4425);
DISPLAY 0.872340 (-2825 4425);
DISPLAY INVISIBLE (-2825 4425);
FORCEPROP 1 LAST PATH I186
J 0
(-3152 4550);
DISPLAY 0.872340 (-3152 4550);
PAINT GREEN (-3152 4550);
DISPLAY INVISIBLE (-3152 4550);
FORCEADD TAP..1
(-3150 4600);
FORCEPROP 3 LASTPIN (-3200 4600) SIG_NAME M_K_CPU0_SA_DQ<24>
J 0
(-3190 4610);
DISPLAY 0.659574 (-3190 4610);
PAINT MONO (-3190 4610);
DISPLAY INVISIBLE (-3190 4610);
FORCEPROP 1 LASTPIN (-3200 4600) BN 24
J 0
(-3212 4608);
DISPLAY 0.489362 (-3212 4608);
PAINT GREEN (-3212 4608);
FORCEPROP 2 LAST CDS_LIB mstr_standard
J 0
(-3150 4600);
DISPLAY 0.723404 (-3150 4600);
PAINT MONO (-3150 4600);
DISPLAY INVISIBLE (-3150 4600);
FORCEPROP 1 LAST BODY_TYPE PLUMBING
J 0
(-3150 4650);
DISPLAY 0.872340 (-3150 4650);
PAINT GREEN (-3150 4650);
DISPLAY INVISIBLE (-3150 4650);
FORCEPROP 1 LAST HDL_TAP TRUE
J 0
(-2825 4475);
DISPLAY 0.872340 (-2825 4475);
DISPLAY INVISIBLE (-2825 4475);
FORCEPROP 1 LAST PATH I187
J 0
(-3152 4600);
DISPLAY 0.872340 (-3152 4600);
PAINT GREEN (-3152 4600);
DISPLAY INVISIBLE (-3152 4600);
FORCEADD TAP..1
(-3150 4500);
FORCEPROP 3 LASTPIN (-3200 4500) SIG_NAME M_K_CPU0_SA_DQ<26>
J 0
(-3190 4510);
DISPLAY 0.659574 (-3190 4510);
PAINT MONO (-3190 4510);
DISPLAY INVISIBLE (-3190 4510);
FORCEPROP 1 LASTPIN (-3200 4500) BN 26
J 0
(-3212 4508);
DISPLAY 0.489362 (-3212 4508);
PAINT GREEN (-3212 4508);
FORCEPROP 2 LAST CDS_LIB mstr_standard
J 0
(-3150 4500);
DISPLAY 0.723404 (-3150 4500);
PAINT MONO (-3150 4500);
DISPLAY INVISIBLE (-3150 4500);
FORCEPROP 1 LAST BODY_TYPE PLUMBING
J 0
(-3150 4550);
DISPLAY 0.872340 (-3150 4550);
PAINT GREEN (-3150 4550);
DISPLAY INVISIBLE (-3150 4550);
FORCEPROP 1 LAST HDL_TAP TRUE
J 0
(-2825 4375);
DISPLAY 0.872340 (-2825 4375);
DISPLAY INVISIBLE (-2825 4375);
FORCEPROP 1 LAST PATH I188
J 0
(-3152 4500);
DISPLAY 0.872340 (-3152 4500);
PAINT GREEN (-3152 4500);
DISPLAY INVISIBLE (-3152 4500);
FORCEADD TAP..1
(-3150 4400);
FORCEPROP 3 LASTPIN (-3200 4400) SIG_NAME M_K_CPU0_SA_DQ<28>
J 0
(-3190 4410);
DISPLAY 0.659574 (-3190 4410);
PAINT MONO (-3190 4410);
DISPLAY INVISIBLE (-3190 4410);
FORCEPROP 1 LASTPIN (-3200 4400) BN 28
J 0
(-3212 4408);
DISPLAY 0.489362 (-3212 4408);
PAINT GREEN (-3212 4408);
FORCEPROP 2 LAST CDS_LIB mstr_standard
J 0
(-3150 4400);
DISPLAY 0.723404 (-3150 4400);
PAINT MONO (-3150 4400);
DISPLAY INVISIBLE (-3150 4400);
FORCEPROP 1 LAST BODY_TYPE PLUMBING
J 0
(-3150 4450);
DISPLAY 0.872340 (-3150 4450);
PAINT GREEN (-3150 4450);
DISPLAY INVISIBLE (-3150 4450);
FORCEPROP 1 LAST HDL_TAP TRUE
J 0
(-2825 4275);
DISPLAY 0.872340 (-2825 4275);
DISPLAY INVISIBLE (-2825 4275);
FORCEPROP 1 LAST PATH I189
J 0
(-3152 4400);
DISPLAY 0.872340 (-3152 4400);
PAINT GREEN (-3152 4400);
DISPLAY INVISIBLE (-3152 4400);
FORCEADD TAP..1
(-3150 4450);
FORCEPROP 3 LASTPIN (-3200 4450) SIG_NAME M_K_CPU0_SA_DQ<27>
J 0
(-3190 4460);
DISPLAY 0.659574 (-3190 4460);
PAINT MONO (-3190 4460);
DISPLAY INVISIBLE (-3190 4460);
FORCEPROP 1 LASTPIN (-3200 4450) BN 27
J 0
(-3212 4458);
DISPLAY 0.489362 (-3212 4458);
PAINT GREEN (-3212 4458);
FORCEPROP 2 LAST CDS_LIB mstr_standard
J 0
(-3150 4450);
DISPLAY 0.723404 (-3150 4450);
PAINT MONO (-3150 4450);
DISPLAY INVISIBLE (-3150 4450);
FORCEPROP 1 LAST BODY_TYPE PLUMBING
J 0
(-3150 4500);
DISPLAY 0.872340 (-3150 4500);
PAINT GREEN (-3150 4500);
DISPLAY INVISIBLE (-3150 4500);
FORCEPROP 1 LAST HDL_TAP TRUE
J 0
(-2825 4325);
DISPLAY 0.872340 (-2825 4325);
DISPLAY INVISIBLE (-2825 4325);
FORCEPROP 1 LAST PATH I190
J 0
(-3152 4450);
DISPLAY 0.872340 (-3152 4450);
PAINT GREEN (-3152 4450);
DISPLAY INVISIBLE (-3152 4450);
FORCEADD TAP..1
(-3150 4350);
FORCEPROP 3 LASTPIN (-3200 4350) SIG_NAME M_K_CPU0_SA_DQ<29>
J 0
(-3190 4360);
DISPLAY 0.659574 (-3190 4360);
PAINT MONO (-3190 4360);
DISPLAY INVISIBLE (-3190 4360);
FORCEPROP 1 LASTPIN (-3200 4350) BN 29
J 0
(-3212 4358);
DISPLAY 0.489362 (-3212 4358);
PAINT GREEN (-3212 4358);
FORCEPROP 2 LAST CDS_LIB mstr_standard
J 0
(-3150 4350);
DISPLAY 0.723404 (-3150 4350);
PAINT MONO (-3150 4350);
DISPLAY INVISIBLE (-3150 4350);
FORCEPROP 1 LAST BODY_TYPE PLUMBING
J 0
(-3150 4400);
DISPLAY 0.872340 (-3150 4400);
PAINT GREEN (-3150 4400);
DISPLAY INVISIBLE (-3150 4400);
FORCEPROP 1 LAST HDL_TAP TRUE
J 0
(-2825 4225);
DISPLAY 0.872340 (-2825 4225);
DISPLAY INVISIBLE (-2825 4225);
FORCEPROP 1 LAST PATH I191
J 0
(-3152 4350);
DISPLAY 0.872340 (-3152 4350);
PAINT GREEN (-3152 4350);
DISPLAY INVISIBLE (-3152 4350);
FORCEADD TAP..1
(-3150 4250);
FORCEPROP 3 LASTPIN (-3200 4250) SIG_NAME M_K_CPU0_SA_DQ<31>
J 0
(-3190 4260);
DISPLAY 0.659574 (-3190 4260);
PAINT MONO (-3190 4260);
DISPLAY INVISIBLE (-3190 4260);
FORCEPROP 1 LASTPIN (-3200 4250) BN 31
J 0
(-3212 4258);
DISPLAY 0.489362 (-3212 4258);
PAINT GREEN (-3212 4258);
FORCEPROP 2 LAST CDS_LIB mstr_standard
J 0
(-3150 4250);
DISPLAY 0.723404 (-3150 4250);
PAINT MONO (-3150 4250);
DISPLAY INVISIBLE (-3150 4250);
FORCEPROP 1 LAST BODY_TYPE PLUMBING
J 0
(-3150 4300);
DISPLAY 0.872340 (-3150 4300);
PAINT GREEN (-3150 4300);
DISPLAY INVISIBLE (-3150 4300);
FORCEPROP 1 LAST HDL_TAP TRUE
J 0
(-2825 4125);
DISPLAY 0.872340 (-2825 4125);
DISPLAY INVISIBLE (-2825 4125);
FORCEPROP 1 LAST PATH I192
J 0
(-3152 4250);
DISPLAY 0.872340 (-3152 4250);
PAINT GREEN (-3152 4250);
DISPLAY INVISIBLE (-3152 4250);
FORCEADD TAP..1
(-3150 4300);
FORCEPROP 3 LASTPIN (-3200 4300) SIG_NAME M_K_CPU0_SA_DQ<30>
J 0
(-3190 4310);
DISPLAY 0.659574 (-3190 4310);
PAINT MONO (-3190 4310);
DISPLAY INVISIBLE (-3190 4310);
FORCEPROP 1 LASTPIN (-3200 4300) BN 30
J 0
(-3212 4308);
DISPLAY 0.489362 (-3212 4308);
PAINT GREEN (-3212 4308);
FORCEPROP 2 LAST CDS_LIB mstr_standard
J 0
(-3150 4300);
DISPLAY 0.723404 (-3150 4300);
PAINT MONO (-3150 4300);
DISPLAY INVISIBLE (-3150 4300);
FORCEPROP 1 LAST BODY_TYPE PLUMBING
J 0
(-3150 4350);
DISPLAY 0.872340 (-3150 4350);
PAINT GREEN (-3150 4350);
DISPLAY INVISIBLE (-3150 4350);
FORCEPROP 1 LAST HDL_TAP TRUE
J 0
(-2825 4175);
DISPLAY 0.872340 (-2825 4175);
DISPLAY INVISIBLE (-2825 4175);
FORCEPROP 1 LAST PATH I193
J 0
(-3152 4300);
DISPLAY 0.872340 (-3152 4300);
PAINT GREEN (-3152 4300);
DISPLAY INVISIBLE (-3152 4300);
FORCEADD TAP..1
(-3150 4100);
FORCEPROP 3 LASTPIN (-3200 4100) SIG_NAME M_K_CPU0_SB_DQ<1>
J 0
(-3190 4110);
DISPLAY 0.659574 (-3190 4110);
PAINT MONO (-3190 4110);
DISPLAY INVISIBLE (-3190 4110);
FORCEPROP 1 LASTPIN (-3200 4100) BN 1
J 0
(-3212 4108);
DISPLAY 0.489362 (-3212 4108);
PAINT GREEN (-3212 4108);
FORCEPROP 2 LAST CDS_LIB mstr_standard
J 0
(-3150 4100);
DISPLAY 0.723404 (-3150 4100);
PAINT MONO (-3150 4100);
DISPLAY INVISIBLE (-3150 4100);
FORCEPROP 1 LAST BODY_TYPE PLUMBING
J 0
(-3150 4150);
DISPLAY 0.872340 (-3150 4150);
PAINT GREEN (-3150 4150);
DISPLAY INVISIBLE (-3150 4150);
FORCEPROP 1 LAST HDL_TAP TRUE
J 0
(-2825 3975);
DISPLAY 0.872340 (-2825 3975);
DISPLAY INVISIBLE (-2825 3975);
FORCEPROP 1 LAST PATH I194
J 0
(-3152 4100);
DISPLAY 0.872340 (-3152 4100);
PAINT GREEN (-3152 4100);
DISPLAY INVISIBLE (-3152 4100);
FORCEADD TAP..1
(-3150 4150);
FORCEPROP 3 LASTPIN (-3200 4150) SIG_NAME M_K_CPU0_SB_DQ<0>
J 0
(-3190 4160);
DISPLAY 0.659574 (-3190 4160);
PAINT MONO (-3190 4160);
DISPLAY INVISIBLE (-3190 4160);
FORCEPROP 1 LASTPIN (-3200 4150) BN 0
J 0
(-3212 4158);
DISPLAY 0.489362 (-3212 4158);
PAINT GREEN (-3212 4158);
FORCEPROP 2 LAST CDS_LIB mstr_standard
J 0
(-3150 4150);
DISPLAY 0.723404 (-3150 4150);
PAINT MONO (-3150 4150);
DISPLAY INVISIBLE (-3150 4150);
FORCEPROP 1 LAST BODY_TYPE PLUMBING
J 0
(-3150 4200);
DISPLAY 0.872340 (-3150 4200);
PAINT GREEN (-3150 4200);
DISPLAY INVISIBLE (-3150 4200);
FORCEPROP 1 LAST HDL_TAP TRUE
J 0
(-2825 4025);
DISPLAY 0.872340 (-2825 4025);
DISPLAY INVISIBLE (-2825 4025);
FORCEPROP 1 LAST PATH I195
J 0
(-3152 4150);
DISPLAY 0.872340 (-3152 4150);
PAINT GREEN (-3152 4150);
DISPLAY INVISIBLE (-3152 4150);
FORCEADD OFFPAGE..6
R 2
(-2550 2400);
FORCEPROP 2 LAST $XR0 96 
J 0
(-2336 2400);
DISPLAY 0.638298 (-2336 2400);
PAINT MONO (-2336 2400);
FORCEPROP 2 LAST CDS_LIB mstr_standard
J 2
(-2550 2400);
DISPLAY 0.723404 (-2550 2400);
PAINT MONO (-2550 2400);
DISPLAY INVISIBLE (-2550 2400);
FORCEPROP 1 LAST OFFPAGE TRUE
J 2
(-2875 2275);
DISPLAY 0.872340 (-2875 2275);
PAINT GREEN (-2875 2275);
DISPLAY INVISIBLE (-2875 2275);
FORCEPROP 1 LAST COMMENT_BODY TRUE
J 2
(-2650 2325);
DISPLAY 0.872340 (-2650 2325);
PAINT GREEN (-2650 2325);
DISPLAY INVISIBLE (-2650 2325);
FORCEPROP 2 LAST PATH I196
J 0
(-2325 2450);
DISPLAY 1.021277 (-2325 2450);
DISPLAY INVISIBLE (-2325 2450);
FORCEADD TAP..1
(-3150 4050);
FORCEPROP 3 LASTPIN (-3200 4050) SIG_NAME M_K_CPU0_SB_DQ<2>
J 0
(-3190 4060);
DISPLAY 0.659574 (-3190 4060);
PAINT MONO (-3190 4060);
DISPLAY INVISIBLE (-3190 4060);
FORCEPROP 1 LASTPIN (-3200 4050) BN 2
J 0
(-3212 4058);
DISPLAY 0.489362 (-3212 4058);
PAINT GREEN (-3212 4058);
FORCEPROP 2 LAST CDS_LIB mstr_standard
J 0
(-3150 4050);
DISPLAY 0.723404 (-3150 4050);
PAINT MONO (-3150 4050);
DISPLAY INVISIBLE (-3150 4050);
FORCEPROP 1 LAST BODY_TYPE PLUMBING
J 0
(-3150 4100);
DISPLAY 0.872340 (-3150 4100);
PAINT GREEN (-3150 4100);
DISPLAY INVISIBLE (-3150 4100);
FORCEPROP 1 LAST HDL_TAP TRUE
J 0
(-2825 3925);
DISPLAY 0.872340 (-2825 3925);
DISPLAY INVISIBLE (-2825 3925);
FORCEPROP 1 LAST PATH I197
J 0
(-3152 4050);
DISPLAY 0.872340 (-3152 4050);
PAINT GREEN (-3152 4050);
DISPLAY INVISIBLE (-3152 4050);
FORCEADD TAP..1
(-3150 4000);
FORCEPROP 3 LASTPIN (-3200 4000) SIG_NAME M_K_CPU0_SB_DQ<3>
J 0
(-3190 4010);
DISPLAY 0.659574 (-3190 4010);
PAINT MONO (-3190 4010);
DISPLAY INVISIBLE (-3190 4010);
FORCEPROP 1 LASTPIN (-3200 4000) BN 3
J 0
(-3212 4008);
DISPLAY 0.489362 (-3212 4008);
PAINT GREEN (-3212 4008);
FORCEPROP 2 LAST CDS_LIB mstr_standard
J 0
(-3150 4000);
DISPLAY 0.723404 (-3150 4000);
PAINT MONO (-3150 4000);
DISPLAY INVISIBLE (-3150 4000);
FORCEPROP 1 LAST BODY_TYPE PLUMBING
J 0
(-3150 4050);
DISPLAY 0.872340 (-3150 4050);
PAINT GREEN (-3150 4050);
DISPLAY INVISIBLE (-3150 4050);
FORCEPROP 1 LAST HDL_TAP TRUE
J 0
(-2825 3875);
DISPLAY 0.872340 (-2825 3875);
DISPLAY INVISIBLE (-2825 3875);
FORCEPROP 1 LAST PATH I198
J 0
(-3152 4000);
DISPLAY 0.872340 (-3152 4000);
PAINT GREEN (-3152 4000);
DISPLAY INVISIBLE (-3152 4000);
FORCEADD TAP..1
(-3150 3900);
FORCEPROP 3 LASTPIN (-3200 3900) SIG_NAME M_K_CPU0_SB_DQ<5>
J 0
(-3190 3910);
DISPLAY 0.659574 (-3190 3910);
PAINT MONO (-3190 3910);
DISPLAY INVISIBLE (-3190 3910);
FORCEPROP 1 LASTPIN (-3200 3900) BN 5
J 0
(-3212 3908);
DISPLAY 0.489362 (-3212 3908);
PAINT GREEN (-3212 3908);
FORCEPROP 2 LAST CDS_LIB mstr_standard
J 0
(-3150 3900);
DISPLAY 0.723404 (-3150 3900);
PAINT MONO (-3150 3900);
DISPLAY INVISIBLE (-3150 3900);
FORCEPROP 1 LAST BODY_TYPE PLUMBING
J 0
(-3150 3950);
DISPLAY 0.872340 (-3150 3950);
PAINT GREEN (-3150 3950);
DISPLAY INVISIBLE (-3150 3950);
FORCEPROP 1 LAST HDL_TAP TRUE
J 0
(-2825 3775);
DISPLAY 0.872340 (-2825 3775);
DISPLAY INVISIBLE (-2825 3775);
FORCEPROP 1 LAST PATH I199
J 0
(-3152 3900);
DISPLAY 0.872340 (-3152 3900);
PAINT GREEN (-3152 3900);
DISPLAY INVISIBLE (-3152 3900);
FORCEADD TAP..1
(-3150 3850);
FORCEPROP 3 LASTPIN (-3200 3850) SIG_NAME M_K_CPU0_SB_DQ<6>
J 0
(-3190 3860);
DISPLAY 0.659574 (-3190 3860);
PAINT MONO (-3190 3860);
DISPLAY INVISIBLE (-3190 3860);
FORCEPROP 1 LASTPIN (-3200 3850) BN 6
J 0
(-3212 3858);
DISPLAY 0.489362 (-3212 3858);
PAINT GREEN (-3212 3858);
FORCEPROP 2 LAST CDS_LIB mstr_standard
J 0
(-3150 3850);
DISPLAY 0.723404 (-3150 3850);
PAINT MONO (-3150 3850);
DISPLAY INVISIBLE (-3150 3850);
FORCEPROP 1 LAST BODY_TYPE PLUMBING
J 0
(-3150 3900);
DISPLAY 0.872340 (-3150 3900);
PAINT GREEN (-3150 3900);
DISPLAY INVISIBLE (-3150 3900);
FORCEPROP 1 LAST HDL_TAP TRUE
J 0
(-2825 3725);
DISPLAY 0.872340 (-2825 3725);
DISPLAY INVISIBLE (-2825 3725);
FORCEPROP 1 LAST PATH I200
J 0
(-3152 3850);
DISPLAY 0.872340 (-3152 3850);
PAINT GREEN (-3152 3850);
DISPLAY INVISIBLE (-3152 3850);
FORCEADD TAP..1
(-3150 3950);
FORCEPROP 3 LASTPIN (-3200 3950) SIG_NAME M_K_CPU0_SB_DQ<4>
J 0
(-3190 3960);
DISPLAY 0.659574 (-3190 3960);
PAINT MONO (-3190 3960);
DISPLAY INVISIBLE (-3190 3960);
FORCEPROP 1 LASTPIN (-3200 3950) BN 4
J 0
(-3212 3958);
DISPLAY 0.489362 (-3212 3958);
PAINT GREEN (-3212 3958);
FORCEPROP 2 LAST CDS_LIB mstr_standard
J 0
(-3150 3950);
DISPLAY 0.723404 (-3150 3950);
PAINT MONO (-3150 3950);
DISPLAY INVISIBLE (-3150 3950);
FORCEPROP 1 LAST BODY_TYPE PLUMBING
J 0
(-3150 4000);
DISPLAY 0.872340 (-3150 4000);
PAINT GREEN (-3150 4000);
DISPLAY INVISIBLE (-3150 4000);
FORCEPROP 1 LAST HDL_TAP TRUE
J 0
(-2825 3825);
DISPLAY 0.872340 (-2825 3825);
DISPLAY INVISIBLE (-2825 3825);
FORCEPROP 1 LAST PATH I201
J 0
(-3152 3950);
DISPLAY 0.872340 (-3152 3950);
PAINT GREEN (-3152 3950);
DISPLAY INVISIBLE (-3152 3950);
FORCEADD TAP..1
(-3150 3800);
FORCEPROP 3 LASTPIN (-3200 3800) SIG_NAME M_K_CPU0_SB_DQ<7>
J 0
(-3190 3810);
DISPLAY 0.659574 (-3190 3810);
PAINT MONO (-3190 3810);
DISPLAY INVISIBLE (-3190 3810);
FORCEPROP 1 LASTPIN (-3200 3800) BN 7
J 0
(-3212 3808);
DISPLAY 0.489362 (-3212 3808);
PAINT GREEN (-3212 3808);
FORCEPROP 2 LAST CDS_LIB mstr_standard
J 0
(-3150 3800);
DISPLAY 0.723404 (-3150 3800);
PAINT MONO (-3150 3800);
DISPLAY INVISIBLE (-3150 3800);
FORCEPROP 1 LAST BODY_TYPE PLUMBING
J 0
(-3150 3850);
DISPLAY 0.872340 (-3150 3850);
PAINT GREEN (-3150 3850);
DISPLAY INVISIBLE (-3150 3850);
FORCEPROP 1 LAST HDL_TAP TRUE
J 0
(-2825 3675);
DISPLAY 0.872340 (-2825 3675);
DISPLAY INVISIBLE (-2825 3675);
FORCEPROP 1 LAST PATH I202
J 0
(-3152 3800);
DISPLAY 0.872340 (-3152 3800);
PAINT GREEN (-3152 3800);
DISPLAY INVISIBLE (-3152 3800);
FORCEADD TAP..1
(-3150 3600);
FORCEPROP 3 LASTPIN (-3200 3600) SIG_NAME M_K_CPU0_SB_DQ<10>
J 0
(-3190 3610);
DISPLAY 0.659574 (-3190 3610);
PAINT MONO (-3190 3610);
DISPLAY INVISIBLE (-3190 3610);
FORCEPROP 1 LASTPIN (-3200 3600) BN 10
J 0
(-3212 3608);
DISPLAY 0.489362 (-3212 3608);
PAINT GREEN (-3212 3608);
FORCEPROP 2 LAST CDS_LIB mstr_standard
J 0
(-3150 3600);
DISPLAY 0.723404 (-3150 3600);
PAINT MONO (-3150 3600);
DISPLAY INVISIBLE (-3150 3600);
FORCEPROP 1 LAST BODY_TYPE PLUMBING
J 0
(-3150 3650);
DISPLAY 0.872340 (-3150 3650);
PAINT GREEN (-3150 3650);
DISPLAY INVISIBLE (-3150 3650);
FORCEPROP 1 LAST HDL_TAP TRUE
J 0
(-2825 3475);
DISPLAY 0.872340 (-2825 3475);
DISPLAY INVISIBLE (-2825 3475);
FORCEPROP 1 LAST PATH I203
J 0
(-3152 3600);
DISPLAY 0.872340 (-3152 3600);
PAINT GREEN (-3152 3600);
DISPLAY INVISIBLE (-3152 3600);
FORCEADD TAP..1
(-3150 3650);
FORCEPROP 3 LASTPIN (-3200 3650) SIG_NAME M_K_CPU0_SB_DQ<9>
J 0
(-3190 3660);
DISPLAY 0.659574 (-3190 3660);
PAINT MONO (-3190 3660);
DISPLAY INVISIBLE (-3190 3660);
FORCEPROP 1 LASTPIN (-3200 3650) BN 9
J 0
(-3212 3658);
DISPLAY 0.489362 (-3212 3658);
PAINT GREEN (-3212 3658);
FORCEPROP 2 LAST CDS_LIB mstr_standard
J 0
(-3150 3650);
DISPLAY 0.723404 (-3150 3650);
PAINT MONO (-3150 3650);
DISPLAY INVISIBLE (-3150 3650);
FORCEPROP 1 LAST BODY_TYPE PLUMBING
J 0
(-3150 3700);
DISPLAY 0.872340 (-3150 3700);
PAINT GREEN (-3150 3700);
DISPLAY INVISIBLE (-3150 3700);
FORCEPROP 1 LAST HDL_TAP TRUE
J 0
(-2825 3525);
DISPLAY 0.872340 (-2825 3525);
DISPLAY INVISIBLE (-2825 3525);
FORCEPROP 1 LAST PATH I204
J 0
(-3152 3650);
DISPLAY 0.872340 (-3152 3650);
PAINT GREEN (-3152 3650);
DISPLAY INVISIBLE (-3152 3650);
FORCEADD TAP..1
(-3150 3700);
FORCEPROP 3 LASTPIN (-3200 3700) SIG_NAME M_K_CPU0_SB_DQ<8>
J 0
(-3190 3710);
DISPLAY 0.659574 (-3190 3710);
PAINT MONO (-3190 3710);
DISPLAY INVISIBLE (-3190 3710);
FORCEPROP 1 LASTPIN (-3200 3700) BN 8
J 0
(-3212 3708);
DISPLAY 0.489362 (-3212 3708);
PAINT GREEN (-3212 3708);
FORCEPROP 2 LAST CDS_LIB mstr_standard
J 0
(-3150 3700);
DISPLAY 0.723404 (-3150 3700);
PAINT MONO (-3150 3700);
DISPLAY INVISIBLE (-3150 3700);
FORCEPROP 1 LAST BODY_TYPE PLUMBING
J 0
(-3150 3750);
DISPLAY 0.872340 (-3150 3750);
PAINT GREEN (-3150 3750);
DISPLAY INVISIBLE (-3150 3750);
FORCEPROP 1 LAST HDL_TAP TRUE
J 0
(-2825 3575);
DISPLAY 0.872340 (-2825 3575);
DISPLAY INVISIBLE (-2825 3575);
FORCEPROP 1 LAST PATH I205
J 0
(-3152 3700);
DISPLAY 0.872340 (-3152 3700);
PAINT GREEN (-3152 3700);
DISPLAY INVISIBLE (-3152 3700);
FORCEADD TAP..1
(-3150 3500);
FORCEPROP 3 LASTPIN (-3200 3500) SIG_NAME M_K_CPU0_SB_DQ<12>
J 0
(-3190 3510);
DISPLAY 0.659574 (-3190 3510);
PAINT MONO (-3190 3510);
DISPLAY INVISIBLE (-3190 3510);
FORCEPROP 1 LASTPIN (-3200 3500) BN 12
J 0
(-3212 3508);
DISPLAY 0.489362 (-3212 3508);
PAINT GREEN (-3212 3508);
FORCEPROP 2 LAST CDS_LIB mstr_standard
J 0
(-3150 3500);
DISPLAY 0.723404 (-3150 3500);
PAINT MONO (-3150 3500);
DISPLAY INVISIBLE (-3150 3500);
FORCEPROP 1 LAST BODY_TYPE PLUMBING
J 0
(-3150 3550);
DISPLAY 0.872340 (-3150 3550);
PAINT GREEN (-3150 3550);
DISPLAY INVISIBLE (-3150 3550);
FORCEPROP 1 LAST HDL_TAP TRUE
J 0
(-2825 3375);
DISPLAY 0.872340 (-2825 3375);
DISPLAY INVISIBLE (-2825 3375);
FORCEPROP 1 LAST PATH I206
J 0
(-3152 3500);
DISPLAY 0.872340 (-3152 3500);
PAINT GREEN (-3152 3500);
DISPLAY INVISIBLE (-3152 3500);
FORCEADD TAP..1
(-3150 3550);
FORCEPROP 3 LASTPIN (-3200 3550) SIG_NAME M_K_CPU0_SB_DQ<11>
J 0
(-3190 3560);
DISPLAY 0.659574 (-3190 3560);
PAINT MONO (-3190 3560);
DISPLAY INVISIBLE (-3190 3560);
FORCEPROP 1 LASTPIN (-3200 3550) BN 11
J 0
(-3212 3558);
DISPLAY 0.489362 (-3212 3558);
PAINT GREEN (-3212 3558);
FORCEPROP 2 LAST CDS_LIB mstr_standard
J 0
(-3150 3550);
DISPLAY 0.723404 (-3150 3550);
PAINT MONO (-3150 3550);
DISPLAY INVISIBLE (-3150 3550);
FORCEPROP 1 LAST BODY_TYPE PLUMBING
J 0
(-3150 3600);
DISPLAY 0.872340 (-3150 3600);
PAINT GREEN (-3150 3600);
DISPLAY INVISIBLE (-3150 3600);
FORCEPROP 1 LAST HDL_TAP TRUE
J 0
(-2825 3425);
DISPLAY 0.872340 (-2825 3425);
DISPLAY INVISIBLE (-2825 3425);
FORCEPROP 1 LAST PATH I207
J 0
(-3152 3550);
DISPLAY 0.872340 (-3152 3550);
PAINT GREEN (-3152 3550);
DISPLAY INVISIBLE (-3152 3550);
FORCEADD TAP..1
(-3150 3400);
FORCEPROP 3 LASTPIN (-3200 3400) SIG_NAME M_K_CPU0_SB_DQ<14>
J 0
(-3190 3410);
DISPLAY 0.659574 (-3190 3410);
PAINT MONO (-3190 3410);
DISPLAY INVISIBLE (-3190 3410);
FORCEPROP 1 LASTPIN (-3200 3400) BN 14
J 0
(-3212 3408);
DISPLAY 0.489362 (-3212 3408);
PAINT GREEN (-3212 3408);
FORCEPROP 2 LAST CDS_LIB mstr_standard
J 0
(-3150 3400);
DISPLAY 0.723404 (-3150 3400);
PAINT MONO (-3150 3400);
DISPLAY INVISIBLE (-3150 3400);
FORCEPROP 1 LAST BODY_TYPE PLUMBING
J 0
(-3150 3450);
DISPLAY 0.872340 (-3150 3450);
PAINT GREEN (-3150 3450);
DISPLAY INVISIBLE (-3150 3450);
FORCEPROP 1 LAST HDL_TAP TRUE
J 0
(-2825 3275);
DISPLAY 0.872340 (-2825 3275);
DISPLAY INVISIBLE (-2825 3275);
FORCEPROP 1 LAST PATH I208
J 0
(-3152 3400);
DISPLAY 0.872340 (-3152 3400);
PAINT GREEN (-3152 3400);
DISPLAY INVISIBLE (-3152 3400);
FORCEADD TAP..1
(-3150 3350);
FORCEPROP 3 LASTPIN (-3200 3350) SIG_NAME M_K_CPU0_SB_DQ<15>
J 0
(-3190 3360);
DISPLAY 0.659574 (-3190 3360);
PAINT MONO (-3190 3360);
DISPLAY INVISIBLE (-3190 3360);
FORCEPROP 1 LASTPIN (-3200 3350) BN 15
J 0
(-3212 3358);
DISPLAY 0.489362 (-3212 3358);
PAINT GREEN (-3212 3358);
FORCEPROP 2 LAST CDS_LIB mstr_standard
J 0
(-3150 3350);
DISPLAY 0.723404 (-3150 3350);
PAINT MONO (-3150 3350);
DISPLAY INVISIBLE (-3150 3350);
FORCEPROP 1 LAST BODY_TYPE PLUMBING
J 0
(-3150 3400);
DISPLAY 0.872340 (-3150 3400);
PAINT GREEN (-3150 3400);
DISPLAY INVISIBLE (-3150 3400);
FORCEPROP 1 LAST HDL_TAP TRUE
J 0
(-2825 3225);
DISPLAY 0.872340 (-2825 3225);
DISPLAY INVISIBLE (-2825 3225);
FORCEPROP 1 LAST PATH I209
J 0
(-3152 3350);
DISPLAY 0.872340 (-3152 3350);
PAINT GREEN (-3152 3350);
DISPLAY INVISIBLE (-3152 3350);
FORCEADD TAP..1
(-3150 3450);
FORCEPROP 3 LASTPIN (-3200 3450) SIG_NAME M_K_CPU0_SB_DQ<13>
J 0
(-3190 3460);
DISPLAY 0.659574 (-3190 3460);
PAINT MONO (-3190 3460);
DISPLAY INVISIBLE (-3190 3460);
FORCEPROP 1 LASTPIN (-3200 3450) BN 13
J 0
(-3212 3458);
DISPLAY 0.489362 (-3212 3458);
PAINT GREEN (-3212 3458);
FORCEPROP 2 LAST CDS_LIB mstr_standard
J 0
(-3150 3450);
DISPLAY 0.723404 (-3150 3450);
PAINT MONO (-3150 3450);
DISPLAY INVISIBLE (-3150 3450);
FORCEPROP 1 LAST BODY_TYPE PLUMBING
J 0
(-3150 3500);
DISPLAY 0.872340 (-3150 3500);
PAINT GREEN (-3150 3500);
DISPLAY INVISIBLE (-3150 3500);
FORCEPROP 1 LAST HDL_TAP TRUE
J 0
(-2825 3325);
DISPLAY 0.872340 (-2825 3325);
DISPLAY INVISIBLE (-2825 3325);
FORCEPROP 1 LAST PATH I210
J 0
(-3152 3450);
DISPLAY 0.872340 (-3152 3450);
PAINT GREEN (-3152 3450);
DISPLAY INVISIBLE (-3152 3450);
FORCEADD TAP..1
(-3150 3250);
FORCEPROP 3 LASTPIN (-3200 3250) SIG_NAME M_K_CPU0_SB_DQ<16>
J 0
(-3190 3260);
DISPLAY 0.659574 (-3190 3260);
PAINT MONO (-3190 3260);
DISPLAY INVISIBLE (-3190 3260);
FORCEPROP 1 LASTPIN (-3200 3250) BN 16
J 0
(-3212 3258);
DISPLAY 0.489362 (-3212 3258);
PAINT GREEN (-3212 3258);
FORCEPROP 2 LAST CDS_LIB mstr_standard
J 0
(-3150 3250);
DISPLAY 0.723404 (-3150 3250);
PAINT MONO (-3150 3250);
DISPLAY INVISIBLE (-3150 3250);
FORCEPROP 1 LAST BODY_TYPE PLUMBING
J 0
(-3150 3300);
DISPLAY 0.872340 (-3150 3300);
PAINT GREEN (-3150 3300);
DISPLAY INVISIBLE (-3150 3300);
FORCEPROP 1 LAST HDL_TAP TRUE
J 0
(-2825 3125);
DISPLAY 0.872340 (-2825 3125);
DISPLAY INVISIBLE (-2825 3125);
FORCEPROP 1 LAST PATH I211
J 0
(-3152 3250);
DISPLAY 0.872340 (-3152 3250);
PAINT GREEN (-3152 3250);
DISPLAY INVISIBLE (-3152 3250);
FORCEADD TAP..1
(-3150 3200);
FORCEPROP 3 LASTPIN (-3200 3200) SIG_NAME M_K_CPU0_SB_DQ<17>
J 0
(-3190 3210);
DISPLAY 0.659574 (-3190 3210);
PAINT MONO (-3190 3210);
DISPLAY INVISIBLE (-3190 3210);
FORCEPROP 1 LASTPIN (-3200 3200) BN 17
J 0
(-3212 3208);
DISPLAY 0.489362 (-3212 3208);
PAINT GREEN (-3212 3208);
FORCEPROP 2 LAST CDS_LIB mstr_standard
J 0
(-3150 3200);
DISPLAY 0.723404 (-3150 3200);
PAINT MONO (-3150 3200);
DISPLAY INVISIBLE (-3150 3200);
FORCEPROP 1 LAST BODY_TYPE PLUMBING
J 0
(-3150 3250);
DISPLAY 0.872340 (-3150 3250);
PAINT GREEN (-3150 3250);
DISPLAY INVISIBLE (-3150 3250);
FORCEPROP 1 LAST HDL_TAP TRUE
J 0
(-2825 3075);
DISPLAY 0.872340 (-2825 3075);
DISPLAY INVISIBLE (-2825 3075);
FORCEPROP 1 LAST PATH I212
J 0
(-3152 3200);
DISPLAY 0.872340 (-3152 3200);
PAINT GREEN (-3152 3200);
DISPLAY INVISIBLE (-3152 3200);
FORCEADD TAP..1
(-3150 3100);
FORCEPROP 3 LASTPIN (-3200 3100) SIG_NAME M_K_CPU0_SB_DQ<19>
J 0
(-3190 3110);
DISPLAY 0.659574 (-3190 3110);
PAINT MONO (-3190 3110);
DISPLAY INVISIBLE (-3190 3110);
FORCEPROP 1 LASTPIN (-3200 3100) BN 19
J 0
(-3212 3108);
DISPLAY 0.489362 (-3212 3108);
PAINT GREEN (-3212 3108);
FORCEPROP 2 LAST CDS_LIB mstr_standard
J 0
(-3150 3100);
DISPLAY 0.723404 (-3150 3100);
PAINT MONO (-3150 3100);
DISPLAY INVISIBLE (-3150 3100);
FORCEPROP 1 LAST BODY_TYPE PLUMBING
J 0
(-3150 3150);
DISPLAY 0.872340 (-3150 3150);
PAINT GREEN (-3150 3150);
DISPLAY INVISIBLE (-3150 3150);
FORCEPROP 1 LAST HDL_TAP TRUE
J 0
(-2825 2975);
DISPLAY 0.872340 (-2825 2975);
DISPLAY INVISIBLE (-2825 2975);
FORCEPROP 1 LAST PATH I213
J 0
(-3152 3100);
DISPLAY 0.872340 (-3152 3100);
PAINT GREEN (-3152 3100);
DISPLAY INVISIBLE (-3152 3100);
FORCEADD TAP..1
(-3150 3150);
FORCEPROP 3 LASTPIN (-3200 3150) SIG_NAME M_K_CPU0_SB_DQ<18>
J 0
(-3190 3160);
DISPLAY 0.659574 (-3190 3160);
PAINT MONO (-3190 3160);
DISPLAY INVISIBLE (-3190 3160);
FORCEPROP 1 LASTPIN (-3200 3150) BN 18
J 0
(-3212 3158);
DISPLAY 0.489362 (-3212 3158);
PAINT GREEN (-3212 3158);
FORCEPROP 2 LAST CDS_LIB mstr_standard
J 0
(-3150 3150);
DISPLAY 0.723404 (-3150 3150);
PAINT MONO (-3150 3150);
DISPLAY INVISIBLE (-3150 3150);
FORCEPROP 1 LAST BODY_TYPE PLUMBING
J 0
(-3150 3200);
DISPLAY 0.872340 (-3150 3200);
PAINT GREEN (-3150 3200);
DISPLAY INVISIBLE (-3150 3200);
FORCEPROP 1 LAST HDL_TAP TRUE
J 0
(-2825 3025);
DISPLAY 0.872340 (-2825 3025);
DISPLAY INVISIBLE (-2825 3025);
FORCEPROP 1 LAST PATH I214
J 0
(-3152 3150);
DISPLAY 0.872340 (-3152 3150);
PAINT GREEN (-3152 3150);
DISPLAY INVISIBLE (-3152 3150);
FORCEADD TAP..1
(-3150 3000);
FORCEPROP 3 LASTPIN (-3200 3000) SIG_NAME M_K_CPU0_SB_DQ<21>
J 0
(-3190 3010);
DISPLAY 0.659574 (-3190 3010);
PAINT MONO (-3190 3010);
DISPLAY INVISIBLE (-3190 3010);
FORCEPROP 1 LASTPIN (-3200 3000) BN 21
J 0
(-3212 3008);
DISPLAY 0.489362 (-3212 3008);
PAINT GREEN (-3212 3008);
FORCEPROP 2 LAST CDS_LIB mstr_standard
J 0
(-3150 3000);
DISPLAY 0.723404 (-3150 3000);
PAINT MONO (-3150 3000);
DISPLAY INVISIBLE (-3150 3000);
FORCEPROP 1 LAST BODY_TYPE PLUMBING
J 0
(-3150 3050);
DISPLAY 0.872340 (-3150 3050);
PAINT GREEN (-3150 3050);
DISPLAY INVISIBLE (-3150 3050);
FORCEPROP 1 LAST HDL_TAP TRUE
J 0
(-2825 2875);
DISPLAY 0.872340 (-2825 2875);
DISPLAY INVISIBLE (-2825 2875);
FORCEPROP 1 LAST PATH I215
J 0
(-3152 3000);
DISPLAY 0.872340 (-3152 3000);
PAINT GREEN (-3152 3000);
DISPLAY INVISIBLE (-3152 3000);
FORCEADD TAP..1
(-3150 3050);
FORCEPROP 3 LASTPIN (-3200 3050) SIG_NAME M_K_CPU0_SB_DQ<20>
J 0
(-3190 3060);
DISPLAY 0.659574 (-3190 3060);
PAINT MONO (-3190 3060);
DISPLAY INVISIBLE (-3190 3060);
FORCEPROP 1 LASTPIN (-3200 3050) BN 20
J 0
(-3212 3058);
DISPLAY 0.489362 (-3212 3058);
PAINT GREEN (-3212 3058);
FORCEPROP 2 LAST CDS_LIB mstr_standard
J 0
(-3150 3050);
DISPLAY 0.723404 (-3150 3050);
PAINT MONO (-3150 3050);
DISPLAY INVISIBLE (-3150 3050);
FORCEPROP 1 LAST BODY_TYPE PLUMBING
J 0
(-3150 3100);
DISPLAY 0.872340 (-3150 3100);
PAINT GREEN (-3150 3100);
DISPLAY INVISIBLE (-3150 3100);
FORCEPROP 1 LAST HDL_TAP TRUE
J 0
(-2825 2925);
DISPLAY 0.872340 (-2825 2925);
DISPLAY INVISIBLE (-2825 2925);
FORCEPROP 1 LAST PATH I216
J 0
(-3152 3050);
DISPLAY 0.872340 (-3152 3050);
PAINT GREEN (-3152 3050);
DISPLAY INVISIBLE (-3152 3050);
FORCEADD TAP..1
(-3150 2950);
FORCEPROP 3 LASTPIN (-3200 2950) SIG_NAME M_K_CPU0_SB_DQ<22>
J 0
(-3190 2960);
DISPLAY 0.659574 (-3190 2960);
PAINT MONO (-3190 2960);
DISPLAY INVISIBLE (-3190 2960);
FORCEPROP 1 LASTPIN (-3200 2950) BN 22
J 0
(-3212 2958);
DISPLAY 0.489362 (-3212 2958);
PAINT GREEN (-3212 2958);
FORCEPROP 2 LAST CDS_LIB mstr_standard
J 0
(-3150 2950);
DISPLAY 0.723404 (-3150 2950);
PAINT MONO (-3150 2950);
DISPLAY INVISIBLE (-3150 2950);
FORCEPROP 1 LAST BODY_TYPE PLUMBING
J 0
(-3150 3000);
DISPLAY 0.872340 (-3150 3000);
PAINT GREEN (-3150 3000);
DISPLAY INVISIBLE (-3150 3000);
FORCEPROP 1 LAST HDL_TAP TRUE
J 0
(-2825 2825);
DISPLAY 0.872340 (-2825 2825);
DISPLAY INVISIBLE (-2825 2825);
FORCEPROP 1 LAST PATH I217
J 0
(-3152 2950);
DISPLAY 0.872340 (-3152 2950);
PAINT GREEN (-3152 2950);
DISPLAY INVISIBLE (-3152 2950);
FORCEADD TAP..1
(-3150 2900);
FORCEPROP 3 LASTPIN (-3200 2900) SIG_NAME M_K_CPU0_SB_DQ<23>
J 0
(-3190 2910);
DISPLAY 0.659574 (-3190 2910);
PAINT MONO (-3190 2910);
DISPLAY INVISIBLE (-3190 2910);
FORCEPROP 1 LASTPIN (-3200 2900) BN 23
J 0
(-3212 2908);
DISPLAY 0.489362 (-3212 2908);
PAINT GREEN (-3212 2908);
FORCEPROP 2 LAST CDS_LIB mstr_standard
J 0
(-3150 2900);
DISPLAY 0.723404 (-3150 2900);
PAINT MONO (-3150 2900);
DISPLAY INVISIBLE (-3150 2900);
FORCEPROP 1 LAST BODY_TYPE PLUMBING
J 0
(-3150 2950);
DISPLAY 0.872340 (-3150 2950);
PAINT GREEN (-3150 2950);
DISPLAY INVISIBLE (-3150 2950);
FORCEPROP 1 LAST HDL_TAP TRUE
J 0
(-2825 2775);
DISPLAY 0.872340 (-2825 2775);
DISPLAY INVISIBLE (-2825 2775);
FORCEPROP 1 LAST PATH I218
J 0
(-3152 2900);
DISPLAY 0.872340 (-3152 2900);
PAINT GREEN (-3152 2900);
DISPLAY INVISIBLE (-3152 2900);
FORCEADD TAP..1
(-3150 2800);
FORCEPROP 3 LASTPIN (-3200 2800) SIG_NAME M_K_CPU0_SB_DQ<24>
J 0
(-3190 2810);
DISPLAY 0.659574 (-3190 2810);
PAINT MONO (-3190 2810);
DISPLAY INVISIBLE (-3190 2810);
FORCEPROP 1 LASTPIN (-3200 2800) BN 24
J 0
(-3212 2808);
DISPLAY 0.489362 (-3212 2808);
PAINT GREEN (-3212 2808);
FORCEPROP 2 LAST CDS_LIB mstr_standard
J 0
(-3150 2800);
DISPLAY 0.723404 (-3150 2800);
PAINT MONO (-3150 2800);
DISPLAY INVISIBLE (-3150 2800);
FORCEPROP 1 LAST BODY_TYPE PLUMBING
J 0
(-3150 2850);
DISPLAY 0.872340 (-3150 2850);
PAINT GREEN (-3150 2850);
DISPLAY INVISIBLE (-3150 2850);
FORCEPROP 1 LAST HDL_TAP TRUE
J 0
(-2825 2675);
DISPLAY 0.872340 (-2825 2675);
DISPLAY INVISIBLE (-2825 2675);
FORCEPROP 1 LAST PATH I219
J 0
(-3152 2800);
DISPLAY 0.872340 (-3152 2800);
PAINT GREEN (-3152 2800);
DISPLAY INVISIBLE (-3152 2800);
FORCEADD TAP..1
(-3150 2750);
FORCEPROP 3 LASTPIN (-3200 2750) SIG_NAME M_K_CPU0_SB_DQ<25>
J 0
(-3190 2760);
DISPLAY 0.659574 (-3190 2760);
PAINT MONO (-3190 2760);
DISPLAY INVISIBLE (-3190 2760);
FORCEPROP 1 LASTPIN (-3200 2750) BN 25
J 0
(-3212 2758);
DISPLAY 0.489362 (-3212 2758);
PAINT GREEN (-3212 2758);
FORCEPROP 2 LAST CDS_LIB mstr_standard
J 0
(-3150 2750);
DISPLAY 0.723404 (-3150 2750);
PAINT MONO (-3150 2750);
DISPLAY INVISIBLE (-3150 2750);
FORCEPROP 1 LAST BODY_TYPE PLUMBING
J 0
(-3150 2800);
DISPLAY 0.872340 (-3150 2800);
PAINT GREEN (-3150 2800);
DISPLAY INVISIBLE (-3150 2800);
FORCEPROP 1 LAST HDL_TAP TRUE
J 0
(-2825 2625);
DISPLAY 0.872340 (-2825 2625);
DISPLAY INVISIBLE (-2825 2625);
FORCEPROP 1 LAST PATH I220
J 0
(-3152 2750);
DISPLAY 0.872340 (-3152 2750);
PAINT GREEN (-3152 2750);
DISPLAY INVISIBLE (-3152 2750);
FORCEADD TAP..1
(-3150 2700);
FORCEPROP 3 LASTPIN (-3200 2700) SIG_NAME M_K_CPU0_SB_DQ<26>
J 0
(-3190 2710);
DISPLAY 0.659574 (-3190 2710);
PAINT MONO (-3190 2710);
DISPLAY INVISIBLE (-3190 2710);
FORCEPROP 1 LASTPIN (-3200 2700) BN 26
J 0
(-3212 2708);
DISPLAY 0.489362 (-3212 2708);
PAINT GREEN (-3212 2708);
FORCEPROP 2 LAST CDS_LIB mstr_standard
J 0
(-3150 2700);
DISPLAY 0.723404 (-3150 2700);
PAINT MONO (-3150 2700);
DISPLAY INVISIBLE (-3150 2700);
FORCEPROP 1 LAST BODY_TYPE PLUMBING
J 0
(-3150 2750);
DISPLAY 0.872340 (-3150 2750);
PAINT GREEN (-3150 2750);
DISPLAY INVISIBLE (-3150 2750);
FORCEPROP 1 LAST HDL_TAP TRUE
J 0
(-2825 2575);
DISPLAY 0.872340 (-2825 2575);
DISPLAY INVISIBLE (-2825 2575);
FORCEPROP 1 LAST PATH I221
J 0
(-3152 2700);
DISPLAY 0.872340 (-3152 2700);
PAINT GREEN (-3152 2700);
DISPLAY INVISIBLE (-3152 2700);
FORCEADD TAP..1
(-3150 2600);
FORCEPROP 3 LASTPIN (-3200 2600) SIG_NAME M_K_CPU0_SB_DQ<28>
J 0
(-3190 2610);
DISPLAY 0.659574 (-3190 2610);
PAINT MONO (-3190 2610);
DISPLAY INVISIBLE (-3190 2610);
FORCEPROP 1 LASTPIN (-3200 2600) BN 28
J 0
(-3212 2608);
DISPLAY 0.489362 (-3212 2608);
PAINT GREEN (-3212 2608);
FORCEPROP 2 LAST CDS_LIB mstr_standard
J 0
(-3150 2600);
DISPLAY 0.723404 (-3150 2600);
PAINT MONO (-3150 2600);
DISPLAY INVISIBLE (-3150 2600);
FORCEPROP 1 LAST BODY_TYPE PLUMBING
J 0
(-3150 2650);
DISPLAY 0.872340 (-3150 2650);
PAINT GREEN (-3150 2650);
DISPLAY INVISIBLE (-3150 2650);
FORCEPROP 1 LAST HDL_TAP TRUE
J 0
(-2825 2475);
DISPLAY 0.872340 (-2825 2475);
DISPLAY INVISIBLE (-2825 2475);
FORCEPROP 1 LAST PATH I222
J 0
(-3152 2600);
DISPLAY 0.872340 (-3152 2600);
PAINT GREEN (-3152 2600);
DISPLAY INVISIBLE (-3152 2600);
FORCEADD TAP..1
(-3150 2650);
FORCEPROP 3 LASTPIN (-3200 2650) SIG_NAME M_K_CPU0_SB_DQ<27>
J 0
(-3190 2660);
DISPLAY 0.659574 (-3190 2660);
PAINT MONO (-3190 2660);
DISPLAY INVISIBLE (-3190 2660);
FORCEPROP 1 LASTPIN (-3200 2650) BN 27
J 0
(-3212 2658);
DISPLAY 0.489362 (-3212 2658);
PAINT GREEN (-3212 2658);
FORCEPROP 2 LAST CDS_LIB mstr_standard
J 0
(-3150 2650);
DISPLAY 0.723404 (-3150 2650);
PAINT MONO (-3150 2650);
DISPLAY INVISIBLE (-3150 2650);
FORCEPROP 1 LAST BODY_TYPE PLUMBING
J 0
(-3150 2700);
DISPLAY 0.872340 (-3150 2700);
PAINT GREEN (-3150 2700);
DISPLAY INVISIBLE (-3150 2700);
FORCEPROP 1 LAST HDL_TAP TRUE
J 0
(-2825 2525);
DISPLAY 0.872340 (-2825 2525);
DISPLAY INVISIBLE (-2825 2525);
FORCEPROP 1 LAST PATH I223
J 0
(-3152 2650);
DISPLAY 0.872340 (-3152 2650);
PAINT GREEN (-3152 2650);
DISPLAY INVISIBLE (-3152 2650);
FORCEADD TAP..1
(-3150 2550);
FORCEPROP 3 LASTPIN (-3200 2550) SIG_NAME M_K_CPU0_SB_DQ<29>
J 0
(-3190 2560);
DISPLAY 0.659574 (-3190 2560);
PAINT MONO (-3190 2560);
DISPLAY INVISIBLE (-3190 2560);
FORCEPROP 1 LASTPIN (-3200 2550) BN 29
J 0
(-3212 2558);
DISPLAY 0.489362 (-3212 2558);
PAINT GREEN (-3212 2558);
FORCEPROP 2 LAST CDS_LIB mstr_standard
J 0
(-3150 2550);
DISPLAY 0.723404 (-3150 2550);
PAINT MONO (-3150 2550);
DISPLAY INVISIBLE (-3150 2550);
FORCEPROP 1 LAST BODY_TYPE PLUMBING
J 0
(-3150 2600);
DISPLAY 0.872340 (-3150 2600);
PAINT GREEN (-3150 2600);
DISPLAY INVISIBLE (-3150 2600);
FORCEPROP 1 LAST HDL_TAP TRUE
J 0
(-2825 2425);
DISPLAY 0.872340 (-2825 2425);
DISPLAY INVISIBLE (-2825 2425);
FORCEPROP 1 LAST PATH I224
J 0
(-3152 2550);
DISPLAY 0.872340 (-3152 2550);
PAINT GREEN (-3152 2550);
DISPLAY INVISIBLE (-3152 2550);
FORCEADD TAP..1
(-3150 2500);
FORCEPROP 3 LASTPIN (-3200 2500) SIG_NAME M_K_CPU0_SB_DQ<30>
J 0
(-3190 2510);
DISPLAY 0.659574 (-3190 2510);
PAINT MONO (-3190 2510);
DISPLAY INVISIBLE (-3190 2510);
FORCEPROP 1 LASTPIN (-3200 2500) BN 30
J 0
(-3212 2508);
DISPLAY 0.489362 (-3212 2508);
PAINT GREEN (-3212 2508);
FORCEPROP 2 LAST CDS_LIB mstr_standard
J 0
(-3150 2500);
DISPLAY 0.723404 (-3150 2500);
PAINT MONO (-3150 2500);
DISPLAY INVISIBLE (-3150 2500);
FORCEPROP 1 LAST BODY_TYPE PLUMBING
J 0
(-3150 2550);
DISPLAY 0.872340 (-3150 2550);
PAINT GREEN (-3150 2550);
DISPLAY INVISIBLE (-3150 2550);
FORCEPROP 1 LAST HDL_TAP TRUE
J 0
(-2825 2375);
DISPLAY 0.872340 (-2825 2375);
DISPLAY INVISIBLE (-2825 2375);
FORCEPROP 1 LAST PATH I225
J 0
(-3152 2500);
DISPLAY 0.872340 (-3152 2500);
PAINT GREEN (-3152 2500);
DISPLAY INVISIBLE (-3152 2500);
FORCEADD TAP..1
(-3150 2450);
FORCEPROP 3 LASTPIN (-3200 2450) SIG_NAME M_K_CPU0_SB_DQ<31>
J 0
(-3190 2460);
DISPLAY 0.659574 (-3190 2460);
PAINT MONO (-3190 2460);
DISPLAY INVISIBLE (-3190 2460);
FORCEPROP 1 LASTPIN (-3200 2450) BN 31
J 0
(-3212 2458);
DISPLAY 0.489362 (-3212 2458);
PAINT GREEN (-3212 2458);
FORCEPROP 2 LAST CDS_LIB mstr_standard
J 0
(-3150 2450);
DISPLAY 0.723404 (-3150 2450);
PAINT MONO (-3150 2450);
DISPLAY INVISIBLE (-3150 2450);
FORCEPROP 1 LAST BODY_TYPE PLUMBING
J 0
(-3150 2500);
DISPLAY 0.872340 (-3150 2500);
PAINT GREEN (-3150 2500);
DISPLAY INVISIBLE (-3150 2500);
FORCEPROP 1 LAST HDL_TAP TRUE
J 0
(-2825 2325);
DISPLAY 0.872340 (-2825 2325);
DISPLAY INVISIBLE (-2825 2325);
FORCEPROP 1 LAST PATH I226
J 0
(-3152 2450);
DISPLAY 0.872340 (-3152 2450);
PAINT GREEN (-3152 2450);
DISPLAY INVISIBLE (-3152 2450);
FORCEADD TAP..1
(-3150 2350);
FORCEPROP 3 LASTPIN (-3200 2350) SIG_NAME M_K_CPU0_SA_CB<0>
J 0
(-3190 2360);
DISPLAY 0.659574 (-3190 2360);
PAINT MONO (-3190 2360);
DISPLAY INVISIBLE (-3190 2360);
FORCEPROP 1 LASTPIN (-3200 2350) BN 0
J 0
(-3212 2358);
DISPLAY 0.489362 (-3212 2358);
PAINT GREEN (-3212 2358);
FORCEPROP 2 LAST CDS_LIB mstr_standard
J 2
(-3150 2350);
DISPLAY 0.723404 (-3150 2350);
PAINT MONO (-3150 2350);
DISPLAY INVISIBLE (-3150 2350);
FORCEPROP 1 LAST BODY_TYPE PLUMBING
J 0
(-3150 2400);
DISPLAY 0.872340 (-3150 2400);
PAINT GREEN (-3150 2400);
DISPLAY INVISIBLE (-3150 2400);
FORCEPROP 1 LAST HDL_TAP TRUE
J 0
(-2825 2225);
DISPLAY 0.872340 (-2825 2225);
DISPLAY INVISIBLE (-2825 2225);
FORCEPROP 1 LAST PATH I227
J 0
(-3152 2350);
DISPLAY 0.872340 (-3152 2350);
PAINT GREEN (-3152 2350);
DISPLAY INVISIBLE (-3152 2350);
FORCEADD TAP..1
(-3150 2300);
FORCEPROP 3 LASTPIN (-3200 2300) SIG_NAME M_K_CPU0_SA_CB<1>
J 0
(-3190 2310);
DISPLAY 0.659574 (-3190 2310);
PAINT MONO (-3190 2310);
DISPLAY INVISIBLE (-3190 2310);
FORCEPROP 1 LASTPIN (-3200 2300) BN 1
J 0
(-3212 2308);
DISPLAY 0.489362 (-3212 2308);
PAINT GREEN (-3212 2308);
FORCEPROP 2 LAST CDS_LIB mstr_standard
J 2
(-3150 2300);
DISPLAY 0.723404 (-3150 2300);
PAINT MONO (-3150 2300);
DISPLAY INVISIBLE (-3150 2300);
FORCEPROP 1 LAST BODY_TYPE PLUMBING
J 0
(-3150 2350);
DISPLAY 0.872340 (-3150 2350);
PAINT GREEN (-3150 2350);
DISPLAY INVISIBLE (-3150 2350);
FORCEPROP 1 LAST HDL_TAP TRUE
J 0
(-2825 2175);
DISPLAY 0.872340 (-2825 2175);
DISPLAY INVISIBLE (-2825 2175);
FORCEPROP 1 LAST PATH I228
J 0
(-3152 2300);
DISPLAY 0.872340 (-3152 2300);
PAINT GREEN (-3152 2300);
DISPLAY INVISIBLE (-3152 2300);
FORCEADD TAP..1
(-3150 2250);
FORCEPROP 3 LASTPIN (-3200 2250) SIG_NAME M_K_CPU0_SA_CB<2>
J 0
(-3190 2260);
DISPLAY 0.659574 (-3190 2260);
PAINT MONO (-3190 2260);
DISPLAY INVISIBLE (-3190 2260);
FORCEPROP 1 LASTPIN (-3200 2250) BN 2
J 0
(-3212 2258);
DISPLAY 0.489362 (-3212 2258);
PAINT GREEN (-3212 2258);
FORCEPROP 2 LAST CDS_LIB mstr_standard
J 2
(-3150 2250);
DISPLAY 0.723404 (-3150 2250);
PAINT MONO (-3150 2250);
DISPLAY INVISIBLE (-3150 2250);
FORCEPROP 1 LAST BODY_TYPE PLUMBING
J 0
(-3150 2300);
DISPLAY 0.872340 (-3150 2300);
PAINT GREEN (-3150 2300);
DISPLAY INVISIBLE (-3150 2300);
FORCEPROP 1 LAST HDL_TAP TRUE
J 0
(-2825 2125);
DISPLAY 0.872340 (-2825 2125);
DISPLAY INVISIBLE (-2825 2125);
FORCEPROP 1 LAST PATH I229
J 0
(-3152 2250);
DISPLAY 0.872340 (-3152 2250);
PAINT GREEN (-3152 2250);
DISPLAY INVISIBLE (-3152 2250);
FORCEADD TAP..1
(-3150 2200);
FORCEPROP 3 LASTPIN (-3200 2200) SIG_NAME M_K_CPU0_SA_CB<3>
J 0
(-3190 2210);
DISPLAY 0.659574 (-3190 2210);
PAINT MONO (-3190 2210);
DISPLAY INVISIBLE (-3190 2210);
FORCEPROP 1 LASTPIN (-3200 2200) BN 3
J 0
(-3212 2208);
DISPLAY 0.489362 (-3212 2208);
PAINT GREEN (-3212 2208);
FORCEPROP 2 LAST CDS_LIB mstr_standard
J 2
(-3150 2200);
DISPLAY 0.723404 (-3150 2200);
PAINT MONO (-3150 2200);
DISPLAY INVISIBLE (-3150 2200);
FORCEPROP 1 LAST BODY_TYPE PLUMBING
J 0
(-3150 2250);
DISPLAY 0.872340 (-3150 2250);
PAINT GREEN (-3150 2250);
DISPLAY INVISIBLE (-3150 2250);
FORCEPROP 1 LAST HDL_TAP TRUE
J 0
(-2825 2075);
DISPLAY 0.872340 (-2825 2075);
DISPLAY INVISIBLE (-2825 2075);
FORCEPROP 1 LAST PATH I230
J 0
(-3152 2200);
DISPLAY 0.872340 (-3152 2200);
PAINT GREEN (-3152 2200);
DISPLAY INVISIBLE (-3152 2200);
FORCEADD TAP..1
(-3150 2050);
FORCEPROP 3 LASTPIN (-3200 2050) SIG_NAME M_K_CPU0_SA_CB<6>
J 0
(-3190 2060);
DISPLAY 0.659574 (-3190 2060);
PAINT MONO (-3190 2060);
DISPLAY INVISIBLE (-3190 2060);
FORCEPROP 1 LASTPIN (-3200 2050) BN 6
J 0
(-3212 2058);
DISPLAY 0.489362 (-3212 2058);
PAINT GREEN (-3212 2058);
FORCEPROP 2 LAST CDS_LIB mstr_standard
J 2
(-3150 2050);
DISPLAY 0.723404 (-3150 2050);
PAINT MONO (-3150 2050);
DISPLAY INVISIBLE (-3150 2050);
FORCEPROP 1 LAST BODY_TYPE PLUMBING
J 0
(-3150 2100);
DISPLAY 0.872340 (-3150 2100);
PAINT GREEN (-3150 2100);
DISPLAY INVISIBLE (-3150 2100);
FORCEPROP 1 LAST HDL_TAP TRUE
J 0
(-2825 1925);
DISPLAY 0.872340 (-2825 1925);
DISPLAY INVISIBLE (-2825 1925);
FORCEPROP 1 LAST PATH I231
J 0
(-3152 2050);
DISPLAY 0.872340 (-3152 2050);
PAINT GREEN (-3152 2050);
DISPLAY INVISIBLE (-3152 2050);
FORCEADD TAP..1
(-3150 2150);
FORCEPROP 3 LASTPIN (-3200 2150) SIG_NAME M_K_CPU0_SA_CB<4>
J 0
(-3190 2160);
DISPLAY 0.659574 (-3190 2160);
PAINT MONO (-3190 2160);
DISPLAY INVISIBLE (-3190 2160);
FORCEPROP 1 LASTPIN (-3200 2150) BN 4
J 0
(-3212 2158);
DISPLAY 0.489362 (-3212 2158);
PAINT GREEN (-3212 2158);
FORCEPROP 2 LAST CDS_LIB mstr_standard
J 2
(-3150 2150);
DISPLAY 0.723404 (-3150 2150);
PAINT MONO (-3150 2150);
DISPLAY INVISIBLE (-3150 2150);
FORCEPROP 1 LAST BODY_TYPE PLUMBING
J 0
(-3150 2200);
DISPLAY 0.872340 (-3150 2200);
PAINT GREEN (-3150 2200);
DISPLAY INVISIBLE (-3150 2200);
FORCEPROP 1 LAST HDL_TAP TRUE
J 0
(-2825 2025);
DISPLAY 0.872340 (-2825 2025);
DISPLAY INVISIBLE (-2825 2025);
FORCEPROP 1 LAST PATH I232
J 0
(-3152 2150);
DISPLAY 0.872340 (-3152 2150);
PAINT GREEN (-3152 2150);
DISPLAY INVISIBLE (-3152 2150);
FORCEADD TAP..1
(-3150 2100);
FORCEPROP 3 LASTPIN (-3200 2100) SIG_NAME M_K_CPU0_SA_CB<5>
J 0
(-3190 2110);
DISPLAY 0.659574 (-3190 2110);
PAINT MONO (-3190 2110);
DISPLAY INVISIBLE (-3190 2110);
FORCEPROP 1 LASTPIN (-3200 2100) BN 5
J 0
(-3212 2108);
DISPLAY 0.489362 (-3212 2108);
PAINT GREEN (-3212 2108);
FORCEPROP 2 LAST CDS_LIB mstr_standard
J 2
(-3150 2100);
DISPLAY 0.723404 (-3150 2100);
PAINT MONO (-3150 2100);
DISPLAY INVISIBLE (-3150 2100);
FORCEPROP 1 LAST BODY_TYPE PLUMBING
J 0
(-3150 2150);
DISPLAY 0.872340 (-3150 2150);
PAINT GREEN (-3150 2150);
DISPLAY INVISIBLE (-3150 2150);
FORCEPROP 1 LAST HDL_TAP TRUE
J 0
(-2825 1975);
DISPLAY 0.872340 (-2825 1975);
DISPLAY INVISIBLE (-2825 1975);
FORCEPROP 1 LAST PATH I233
J 0
(-3152 2100);
DISPLAY 0.872340 (-3152 2100);
PAINT GREEN (-3152 2100);
DISPLAY INVISIBLE (-3152 2100);
FORCEADD OFFPAGE..6
R 2
(-2550 1950);
FORCEPROP 2 LAST $XR0 96 
J 0
(-2336 1950);
DISPLAY 0.638298 (-2336 1950);
PAINT MONO (-2336 1950);
FORCEPROP 2 LAST CDS_LIB mstr_standard
J 2
(-2550 1950);
DISPLAY 0.723404 (-2550 1950);
PAINT MONO (-2550 1950);
DISPLAY INVISIBLE (-2550 1950);
FORCEPROP 1 LAST OFFPAGE TRUE
J 2
(-2875 1825);
DISPLAY 0.872340 (-2875 1825);
PAINT GREEN (-2875 1825);
DISPLAY INVISIBLE (-2875 1825);
FORCEPROP 1 LAST COMMENT_BODY TRUE
J 2
(-2650 1875);
DISPLAY 0.872340 (-2650 1875);
PAINT GREEN (-2650 1875);
DISPLAY INVISIBLE (-2650 1875);
FORCEPROP 2 LAST PATH I234
J 0
(-2325 2000);
DISPLAY 1.021277 (-2325 2000);
DISPLAY INVISIBLE (-2325 2000);
FORCEADD TAP..1
(-3150 2000);
FORCEPROP 3 LASTPIN (-3200 2000) SIG_NAME M_K_CPU0_SA_CB<7>
J 0
(-3190 2010);
DISPLAY 0.659574 (-3190 2010);
PAINT MONO (-3190 2010);
DISPLAY INVISIBLE (-3190 2010);
FORCEPROP 1 LASTPIN (-3200 2000) BN 7
J 0
(-3212 2008);
DISPLAY 0.489362 (-3212 2008);
PAINT GREEN (-3212 2008);
FORCEPROP 2 LAST CDS_LIB mstr_standard
J 2
(-3150 2000);
DISPLAY 0.723404 (-3150 2000);
PAINT MONO (-3150 2000);
DISPLAY INVISIBLE (-3150 2000);
FORCEPROP 1 LAST BODY_TYPE PLUMBING
J 0
(-3150 2050);
DISPLAY 0.872340 (-3150 2050);
PAINT GREEN (-3150 2050);
DISPLAY INVISIBLE (-3150 2050);
FORCEPROP 1 LAST HDL_TAP TRUE
J 0
(-2825 1875);
DISPLAY 0.872340 (-2825 1875);
DISPLAY INVISIBLE (-2825 1875);
FORCEPROP 1 LAST PATH I235
J 0
(-3152 2000);
DISPLAY 0.872340 (-3152 2000);
PAINT GREEN (-3152 2000);
DISPLAY INVISIBLE (-3152 2000);
FORCEADD TAP..1
(-3150 1800);
FORCEPROP 3 LASTPIN (-3200 1800) SIG_NAME M_K_CPU0_SB_CB<2>
J 0
(-3190 1810);
DISPLAY 0.659574 (-3190 1810);
PAINT MONO (-3190 1810);
DISPLAY INVISIBLE (-3190 1810);
FORCEPROP 1 LASTPIN (-3200 1800) BN 2
J 0
(-3212 1808);
DISPLAY 0.489362 (-3212 1808);
PAINT GREEN (-3212 1808);
FORCEPROP 2 LAST CDS_LIB mstr_standard
J 2
(-3150 1800);
DISPLAY 0.723404 (-3150 1800);
PAINT MONO (-3150 1800);
DISPLAY INVISIBLE (-3150 1800);
FORCEPROP 1 LAST BODY_TYPE PLUMBING
J 0
(-3150 1850);
DISPLAY 0.872340 (-3150 1850);
PAINT GREEN (-3150 1850);
DISPLAY INVISIBLE (-3150 1850);
FORCEPROP 1 LAST HDL_TAP TRUE
J 0
(-2825 1675);
DISPLAY 0.872340 (-2825 1675);
DISPLAY INVISIBLE (-2825 1675);
FORCEPROP 1 LAST PATH I236
J 0
(-3152 1800);
DISPLAY 0.872340 (-3152 1800);
PAINT GREEN (-3152 1800);
DISPLAY INVISIBLE (-3152 1800);
FORCEADD TAP..1
(-3150 1850);
FORCEPROP 3 LASTPIN (-3200 1850) SIG_NAME M_K_CPU0_SB_CB<1>
J 0
(-3190 1860);
DISPLAY 0.659574 (-3190 1860);
PAINT MONO (-3190 1860);
DISPLAY INVISIBLE (-3190 1860);
FORCEPROP 1 LASTPIN (-3200 1850) BN 1
J 0
(-3212 1858);
DISPLAY 0.489362 (-3212 1858);
PAINT GREEN (-3212 1858);
FORCEPROP 2 LAST CDS_LIB mstr_standard
J 2
(-3150 1850);
DISPLAY 0.723404 (-3150 1850);
PAINT MONO (-3150 1850);
DISPLAY INVISIBLE (-3150 1850);
FORCEPROP 1 LAST BODY_TYPE PLUMBING
J 0
(-3150 1900);
DISPLAY 0.872340 (-3150 1900);
PAINT GREEN (-3150 1900);
DISPLAY INVISIBLE (-3150 1900);
FORCEPROP 1 LAST HDL_TAP TRUE
J 0
(-2825 1725);
DISPLAY 0.872340 (-2825 1725);
DISPLAY INVISIBLE (-2825 1725);
FORCEPROP 1 LAST PATH I237
J 0
(-3152 1850);
DISPLAY 0.872340 (-3152 1850);
PAINT GREEN (-3152 1850);
DISPLAY INVISIBLE (-3152 1850);
FORCEADD TAP..1
(-3150 1900);
FORCEPROP 3 LASTPIN (-3200 1900) SIG_NAME M_K_CPU0_SB_CB<0>
J 0
(-3190 1910);
DISPLAY 0.659574 (-3190 1910);
PAINT MONO (-3190 1910);
DISPLAY INVISIBLE (-3190 1910);
FORCEPROP 1 LASTPIN (-3200 1900) BN 0
J 0
(-3212 1908);
DISPLAY 0.489362 (-3212 1908);
PAINT GREEN (-3212 1908);
FORCEPROP 2 LAST CDS_LIB mstr_standard
J 2
(-3150 1900);
DISPLAY 0.723404 (-3150 1900);
PAINT MONO (-3150 1900);
DISPLAY INVISIBLE (-3150 1900);
FORCEPROP 1 LAST BODY_TYPE PLUMBING
J 0
(-3150 1950);
DISPLAY 0.872340 (-3150 1950);
PAINT GREEN (-3150 1950);
DISPLAY INVISIBLE (-3150 1950);
FORCEPROP 1 LAST HDL_TAP TRUE
J 0
(-2825 1775);
DISPLAY 0.872340 (-2825 1775);
DISPLAY INVISIBLE (-2825 1775);
FORCEPROP 1 LAST PATH I238
J 0
(-3152 1900);
DISPLAY 0.872340 (-3152 1900);
PAINT GREEN (-3152 1900);
DISPLAY INVISIBLE (-3152 1900);
FORCEADD TAP..1
(-3150 1750);
FORCEPROP 3 LASTPIN (-3200 1750) SIG_NAME M_K_CPU0_SB_CB<3>
J 0
(-3190 1760);
DISPLAY 0.659574 (-3190 1760);
PAINT MONO (-3190 1760);
DISPLAY INVISIBLE (-3190 1760);
FORCEPROP 1 LASTPIN (-3200 1750) BN 3
J 0
(-3212 1758);
DISPLAY 0.489362 (-3212 1758);
PAINT GREEN (-3212 1758);
FORCEPROP 2 LAST CDS_LIB mstr_standard
J 2
(-3150 1750);
DISPLAY 0.723404 (-3150 1750);
PAINT MONO (-3150 1750);
DISPLAY INVISIBLE (-3150 1750);
FORCEPROP 1 LAST BODY_TYPE PLUMBING
J 0
(-3150 1800);
DISPLAY 0.872340 (-3150 1800);
PAINT GREEN (-3150 1800);
DISPLAY INVISIBLE (-3150 1800);
FORCEPROP 1 LAST HDL_TAP TRUE
J 0
(-2825 1625);
DISPLAY 0.872340 (-2825 1625);
DISPLAY INVISIBLE (-2825 1625);
FORCEPROP 1 LAST PATH I239
J 0
(-3152 1750);
DISPLAY 0.872340 (-3152 1750);
PAINT GREEN (-3152 1750);
DISPLAY INVISIBLE (-3152 1750);
FORCEADD TAP..1
(-3150 1700);
FORCEPROP 3 LASTPIN (-3200 1700) SIG_NAME M_K_CPU0_SB_CB<4>
J 0
(-3190 1710);
DISPLAY 0.659574 (-3190 1710);
PAINT MONO (-3190 1710);
DISPLAY INVISIBLE (-3190 1710);
FORCEPROP 1 LASTPIN (-3200 1700) BN 4
J 0
(-3212 1708);
DISPLAY 0.489362 (-3212 1708);
PAINT GREEN (-3212 1708);
FORCEPROP 2 LAST CDS_LIB mstr_standard
J 2
(-3150 1700);
DISPLAY 0.723404 (-3150 1700);
PAINT MONO (-3150 1700);
DISPLAY INVISIBLE (-3150 1700);
FORCEPROP 1 LAST BODY_TYPE PLUMBING
J 0
(-3150 1750);
DISPLAY 0.872340 (-3150 1750);
PAINT GREEN (-3150 1750);
DISPLAY INVISIBLE (-3150 1750);
FORCEPROP 1 LAST HDL_TAP TRUE
J 0
(-2825 1575);
DISPLAY 0.872340 (-2825 1575);
DISPLAY INVISIBLE (-2825 1575);
FORCEPROP 1 LAST PATH I240
J 0
(-3152 1700);
DISPLAY 0.872340 (-3152 1700);
PAINT GREEN (-3152 1700);
DISPLAY INVISIBLE (-3152 1700);
FORCEADD TAP..1
(-3150 1550);
FORCEPROP 3 LASTPIN (-3200 1550) SIG_NAME M_K_CPU0_SB_CB<7>
J 0
(-3190 1560);
DISPLAY 0.659574 (-3190 1560);
PAINT MONO (-3190 1560);
DISPLAY INVISIBLE (-3190 1560);
FORCEPROP 1 LASTPIN (-3200 1550) BN 7
J 0
(-3212 1558);
DISPLAY 0.489362 (-3212 1558);
PAINT GREEN (-3212 1558);
FORCEPROP 2 LAST CDS_LIB mstr_standard
J 2
(-3150 1550);
DISPLAY 0.723404 (-3150 1550);
PAINT MONO (-3150 1550);
DISPLAY INVISIBLE (-3150 1550);
FORCEPROP 1 LAST BODY_TYPE PLUMBING
J 0
(-3150 1600);
DISPLAY 0.872340 (-3150 1600);
PAINT GREEN (-3150 1600);
DISPLAY INVISIBLE (-3150 1600);
FORCEPROP 1 LAST HDL_TAP TRUE
J 0
(-2825 1425);
DISPLAY 0.872340 (-2825 1425);
DISPLAY INVISIBLE (-2825 1425);
FORCEPROP 1 LAST PATH I241
J 0
(-3152 1550);
DISPLAY 0.872340 (-3152 1550);
PAINT GREEN (-3152 1550);
DISPLAY INVISIBLE (-3152 1550);
FORCEADD TAP..1
(-3150 1600);
FORCEPROP 3 LASTPIN (-3200 1600) SIG_NAME M_K_CPU0_SB_CB<6>
J 0
(-3190 1610);
DISPLAY 0.659574 (-3190 1610);
PAINT MONO (-3190 1610);
DISPLAY INVISIBLE (-3190 1610);
FORCEPROP 1 LASTPIN (-3200 1600) BN 6
J 0
(-3212 1608);
DISPLAY 0.489362 (-3212 1608);
PAINT GREEN (-3212 1608);
FORCEPROP 2 LAST CDS_LIB mstr_standard
J 2
(-3150 1600);
DISPLAY 0.723404 (-3150 1600);
PAINT MONO (-3150 1600);
DISPLAY INVISIBLE (-3150 1600);
FORCEPROP 1 LAST BODY_TYPE PLUMBING
J 0
(-3150 1650);
DISPLAY 0.872340 (-3150 1650);
PAINT GREEN (-3150 1650);
DISPLAY INVISIBLE (-3150 1650);
FORCEPROP 1 LAST HDL_TAP TRUE
J 0
(-2825 1475);
DISPLAY 0.872340 (-2825 1475);
DISPLAY INVISIBLE (-2825 1475);
FORCEPROP 1 LAST PATH I242
J 0
(-3152 1600);
DISPLAY 0.872340 (-3152 1600);
PAINT GREEN (-3152 1600);
DISPLAY INVISIBLE (-3152 1600);
FORCEADD TAP..1
(-3150 1650);
FORCEPROP 3 LASTPIN (-3200 1650) SIG_NAME M_K_CPU0_SB_CB<5>
J 0
(-3190 1660);
DISPLAY 0.659574 (-3190 1660);
PAINT MONO (-3190 1660);
DISPLAY INVISIBLE (-3190 1660);
FORCEPROP 1 LASTPIN (-3200 1650) BN 5
J 0
(-3212 1658);
DISPLAY 0.489362 (-3212 1658);
PAINT GREEN (-3212 1658);
FORCEPROP 2 LAST CDS_LIB mstr_standard
J 2
(-3150 1650);
DISPLAY 0.723404 (-3150 1650);
PAINT MONO (-3150 1650);
DISPLAY INVISIBLE (-3150 1650);
FORCEPROP 1 LAST BODY_TYPE PLUMBING
J 0
(-3150 1700);
DISPLAY 0.872340 (-3150 1700);
PAINT GREEN (-3150 1700);
DISPLAY INVISIBLE (-3150 1700);
FORCEPROP 1 LAST HDL_TAP TRUE
J 0
(-2825 1525);
DISPLAY 0.872340 (-2825 1525);
DISPLAY INVISIBLE (-2825 1525);
FORCEPROP 1 LAST PATH I243
J 0
(-3152 1650);
DISPLAY 0.872340 (-3152 1650);
PAINT GREEN (-3152 1650);
DISPLAY INVISIBLE (-3152 1650);
FORCEADD TAP..1
R 2
(-5575 5950);
FORCEPROP 3 LASTPIN (-5525 5950) SIG_NAME M_K_CPU0_SA_DQS_DP<0>
J 0
(-5515 5960);
DISPLAY 0.659574 (-5515 5960);
PAINT MONO (-5515 5960);
DISPLAY INVISIBLE (-5515 5960);
FORCEPROP 1 LASTPIN (-5525 5950) BN 0
J 2
(-5513 5958);
DISPLAY 0.489362 (-5513 5958);
PAINT GREEN (-5513 5958);
FORCEPROP 2 LAST CDS_LIB mstr_standard
J 2
(-5575 5950);
DISPLAY 0.723404 (-5575 5950);
PAINT MONO (-5575 5950);
DISPLAY INVISIBLE (-5575 5950);
FORCEPROP 1 LAST BODY_TYPE PLUMBING
J 2
(-5575 6000);
DISPLAY 0.872340 (-5575 6000);
PAINT GREEN (-5575 6000);
DISPLAY INVISIBLE (-5575 6000);
FORCEPROP 1 LAST HDL_TAP TRUE
J 2
(-5900 5825);
DISPLAY 0.872340 (-5900 5825);
DISPLAY INVISIBLE (-5900 5825);
FORCEPROP 1 LAST PATH I244
J 2
(-5573 5950);
DISPLAY 0.872340 (-5573 5950);
PAINT GREEN (-5573 5950);
DISPLAY INVISIBLE (-5573 5950);
FORCEADD TAP..1
R 2
(-5575 5850);
FORCEPROP 3 LASTPIN (-5525 5850) SIG_NAME M_K_CPU0_SA_DQS_DP<1>
J 0
(-5515 5860);
DISPLAY 0.659574 (-5515 5860);
PAINT MONO (-5515 5860);
DISPLAY INVISIBLE (-5515 5860);
FORCEPROP 1 LASTPIN (-5525 5850) BN 1
J 2
(-5513 5858);
DISPLAY 0.489362 (-5513 5858);
PAINT GREEN (-5513 5858);
FORCEPROP 2 LAST CDS_LIB mstr_standard
J 2
(-5575 5850);
DISPLAY 0.723404 (-5575 5850);
PAINT MONO (-5575 5850);
DISPLAY INVISIBLE (-5575 5850);
FORCEPROP 1 LAST BODY_TYPE PLUMBING
J 2
(-5575 5900);
DISPLAY 0.872340 (-5575 5900);
PAINT GREEN (-5575 5900);
DISPLAY INVISIBLE (-5575 5900);
FORCEPROP 1 LAST HDL_TAP TRUE
J 2
(-5900 5725);
DISPLAY 0.872340 (-5900 5725);
DISPLAY INVISIBLE (-5900 5725);
FORCEPROP 1 LAST PATH I245
J 2
(-5573 5850);
DISPLAY 0.872340 (-5573 5850);
PAINT GREEN (-5573 5850);
DISPLAY INVISIBLE (-5573 5850);
FORCEADD TAP..1
R 2
(-5575 5750);
FORCEPROP 3 LASTPIN (-5525 5750) SIG_NAME M_K_CPU0_SA_DQS_DP<2>
J 0
(-5515 5760);
DISPLAY 0.659574 (-5515 5760);
PAINT MONO (-5515 5760);
DISPLAY INVISIBLE (-5515 5760);
FORCEPROP 1 LASTPIN (-5525 5750) BN 2
J 2
(-5513 5758);
DISPLAY 0.489362 (-5513 5758);
PAINT GREEN (-5513 5758);
FORCEPROP 2 LAST CDS_LIB mstr_standard
J 2
(-5575 5750);
DISPLAY 0.723404 (-5575 5750);
PAINT MONO (-5575 5750);
DISPLAY INVISIBLE (-5575 5750);
FORCEPROP 1 LAST BODY_TYPE PLUMBING
J 2
(-5575 5800);
DISPLAY 0.872340 (-5575 5800);
PAINT GREEN (-5575 5800);
DISPLAY INVISIBLE (-5575 5800);
FORCEPROP 1 LAST HDL_TAP TRUE
J 2
(-5900 5625);
DISPLAY 0.872340 (-5900 5625);
DISPLAY INVISIBLE (-5900 5625);
FORCEPROP 1 LAST PATH I246
J 2
(-5573 5750);
DISPLAY 0.872340 (-5573 5750);
PAINT GREEN (-5573 5750);
DISPLAY INVISIBLE (-5573 5750);
FORCEADD TAP..1
R 2
(-5575 5650);
FORCEPROP 3 LASTPIN (-5525 5650) SIG_NAME M_K_CPU0_SA_DQS_DP<3>
J 0
(-5515 5660);
DISPLAY 0.659574 (-5515 5660);
PAINT MONO (-5515 5660);
DISPLAY INVISIBLE (-5515 5660);
FORCEPROP 1 LASTPIN (-5525 5650) BN 3
J 2
(-5513 5658);
DISPLAY 0.489362 (-5513 5658);
PAINT GREEN (-5513 5658);
FORCEPROP 2 LAST CDS_LIB mstr_standard
J 2
(-5575 5650);
DISPLAY 0.723404 (-5575 5650);
PAINT MONO (-5575 5650);
DISPLAY INVISIBLE (-5575 5650);
FORCEPROP 1 LAST BODY_TYPE PLUMBING
J 2
(-5575 5700);
DISPLAY 0.872340 (-5575 5700);
PAINT GREEN (-5575 5700);
DISPLAY INVISIBLE (-5575 5700);
FORCEPROP 1 LAST HDL_TAP TRUE
J 2
(-5900 5525);
DISPLAY 0.872340 (-5900 5525);
DISPLAY INVISIBLE (-5900 5525);
FORCEPROP 1 LAST PATH I247
J 2
(-5573 5650);
DISPLAY 0.872340 (-5573 5650);
PAINT GREEN (-5573 5650);
DISPLAY INVISIBLE (-5573 5650);
FORCEADD TAP..1
R 2
(-5575 5450);
FORCEPROP 3 LASTPIN (-5525 5450) SIG_NAME M_K_CPU0_SA_DQS_DP<5>
J 0
(-5515 5460);
DISPLAY 0.659574 (-5515 5460);
PAINT MONO (-5515 5460);
DISPLAY INVISIBLE (-5515 5460);
FORCEPROP 1 LASTPIN (-5525 5450) BN 5
J 2
(-5513 5458);
DISPLAY 0.489362 (-5513 5458);
PAINT GREEN (-5513 5458);
FORCEPROP 2 LAST CDS_LIB mstr_standard
J 2
(-5575 5450);
DISPLAY 0.723404 (-5575 5450);
PAINT MONO (-5575 5450);
DISPLAY INVISIBLE (-5575 5450);
FORCEPROP 1 LAST BODY_TYPE PLUMBING
J 2
(-5575 5500);
DISPLAY 0.872340 (-5575 5500);
PAINT GREEN (-5575 5500);
DISPLAY INVISIBLE (-5575 5500);
FORCEPROP 1 LAST HDL_TAP TRUE
J 2
(-5900 5325);
DISPLAY 0.872340 (-5900 5325);
DISPLAY INVISIBLE (-5900 5325);
FORCEPROP 1 LAST PATH I248
J 2
(-5573 5450);
DISPLAY 0.872340 (-5573 5450);
PAINT GREEN (-5573 5450);
DISPLAY INVISIBLE (-5573 5450);
FORCEADD TAP..1
R 2
(-5575 5550);
FORCEPROP 3 LASTPIN (-5525 5550) SIG_NAME M_K_CPU0_SA_DQS_DP<4>
J 0
(-5515 5560);
DISPLAY 0.659574 (-5515 5560);
PAINT MONO (-5515 5560);
DISPLAY INVISIBLE (-5515 5560);
FORCEPROP 1 LASTPIN (-5525 5550) BN 4
J 2
(-5513 5558);
DISPLAY 0.489362 (-5513 5558);
PAINT GREEN (-5513 5558);
FORCEPROP 2 LAST CDS_LIB mstr_standard
J 2
(-5575 5550);
DISPLAY 0.723404 (-5575 5550);
PAINT MONO (-5575 5550);
DISPLAY INVISIBLE (-5575 5550);
FORCEPROP 1 LAST BODY_TYPE PLUMBING
J 2
(-5575 5600);
DISPLAY 0.872340 (-5575 5600);
PAINT GREEN (-5575 5600);
DISPLAY INVISIBLE (-5575 5600);
FORCEPROP 1 LAST HDL_TAP TRUE
J 2
(-5900 5425);
DISPLAY 0.872340 (-5900 5425);
DISPLAY INVISIBLE (-5900 5425);
FORCEPROP 1 LAST PATH I249
J 2
(-5573 5550);
DISPLAY 0.872340 (-5573 5550);
PAINT GREEN (-5573 5550);
DISPLAY INVISIBLE (-5573 5550);
FORCEADD TAP..1
R 2
(-5575 5250);
FORCEPROP 3 LASTPIN (-5525 5250) SIG_NAME M_K_CPU0_SA_DQS_DP<7>
J 0
(-5515 5260);
DISPLAY 0.659574 (-5515 5260);
PAINT MONO (-5515 5260);
DISPLAY INVISIBLE (-5515 5260);
FORCEPROP 1 LASTPIN (-5525 5250) BN 7
J 2
(-5513 5258);
DISPLAY 0.489362 (-5513 5258);
PAINT GREEN (-5513 5258);
FORCEPROP 2 LAST CDS_LIB mstr_standard
J 2
(-5575 5250);
DISPLAY 0.723404 (-5575 5250);
PAINT MONO (-5575 5250);
DISPLAY INVISIBLE (-5575 5250);
FORCEPROP 1 LAST BODY_TYPE PLUMBING
J 2
(-5575 5300);
DISPLAY 0.872340 (-5575 5300);
PAINT GREEN (-5575 5300);
DISPLAY INVISIBLE (-5575 5300);
FORCEPROP 1 LAST HDL_TAP TRUE
J 2
(-5900 5125);
DISPLAY 0.872340 (-5900 5125);
DISPLAY INVISIBLE (-5900 5125);
FORCEPROP 1 LAST PATH I250
J 2
(-5573 5250);
DISPLAY 0.872340 (-5573 5250);
PAINT GREEN (-5573 5250);
DISPLAY INVISIBLE (-5573 5250);
FORCEADD TAP..1
R 2
(-5575 5350);
FORCEPROP 3 LASTPIN (-5525 5350) SIG_NAME M_K_CPU0_SA_DQS_DP<6>
J 0
(-5515 5360);
DISPLAY 0.659574 (-5515 5360);
PAINT MONO (-5515 5360);
DISPLAY INVISIBLE (-5515 5360);
FORCEPROP 1 LASTPIN (-5525 5350) BN 6
J 2
(-5513 5358);
DISPLAY 0.489362 (-5513 5358);
PAINT GREEN (-5513 5358);
FORCEPROP 2 LAST CDS_LIB mstr_standard
J 2
(-5575 5350);
DISPLAY 0.723404 (-5575 5350);
PAINT MONO (-5575 5350);
DISPLAY INVISIBLE (-5575 5350);
FORCEPROP 1 LAST BODY_TYPE PLUMBING
J 2
(-5575 5400);
DISPLAY 0.872340 (-5575 5400);
PAINT GREEN (-5575 5400);
DISPLAY INVISIBLE (-5575 5400);
FORCEPROP 1 LAST HDL_TAP TRUE
J 2
(-5900 5225);
DISPLAY 0.872340 (-5900 5225);
DISPLAY INVISIBLE (-5900 5225);
FORCEPROP 1 LAST PATH I251
J 2
(-5573 5350);
DISPLAY 0.872340 (-5573 5350);
PAINT GREEN (-5573 5350);
DISPLAY INVISIBLE (-5573 5350);
FORCEADD TAP..1
R 2
(-5575 5150);
FORCEPROP 3 LASTPIN (-5525 5150) SIG_NAME M_K_CPU0_SA_DQS_DP<8>
J 0
(-5515 5160);
DISPLAY 0.659574 (-5515 5160);
PAINT MONO (-5515 5160);
DISPLAY INVISIBLE (-5515 5160);
FORCEPROP 1 LASTPIN (-5525 5150) BN 8
J 2
(-5513 5158);
DISPLAY 0.489362 (-5513 5158);
PAINT GREEN (-5513 5158);
FORCEPROP 2 LAST CDS_LIB mstr_standard
J 2
(-5575 5150);
DISPLAY 0.723404 (-5575 5150);
PAINT MONO (-5575 5150);
DISPLAY INVISIBLE (-5575 5150);
FORCEPROP 1 LAST BODY_TYPE PLUMBING
J 2
(-5575 5200);
DISPLAY 0.872340 (-5575 5200);
PAINT GREEN (-5575 5200);
DISPLAY INVISIBLE (-5575 5200);
FORCEPROP 1 LAST HDL_TAP TRUE
J 2
(-5900 5025);
DISPLAY 0.872340 (-5900 5025);
DISPLAY INVISIBLE (-5900 5025);
FORCEPROP 1 LAST PATH I252
J 2
(-5573 5150);
DISPLAY 0.872340 (-5573 5150);
PAINT GREEN (-5573 5150);
DISPLAY INVISIBLE (-5573 5150);
FORCEADD TAP..1
R 2
(-5775 5900);
FORCEPROP 3 LASTPIN (-5725 5900) SIG_NAME M_K_CPU0_SA_DQS_DN<0>
J 0
(-5715 5910);
DISPLAY 0.659574 (-5715 5910);
PAINT MONO (-5715 5910);
DISPLAY INVISIBLE (-5715 5910);
FORCEPROP 1 LASTPIN (-5725 5900) BN 0
J 2
(-5713 5908);
DISPLAY 0.489362 (-5713 5908);
PAINT GREEN (-5713 5908);
FORCEPROP 2 LAST CDS_LIB mstr_standard
J 2
(-5775 5900);
DISPLAY 0.723404 (-5775 5900);
PAINT MONO (-5775 5900);
DISPLAY INVISIBLE (-5775 5900);
FORCEPROP 1 LAST BODY_TYPE PLUMBING
J 2
(-5775 5950);
DISPLAY 0.872340 (-5775 5950);
PAINT GREEN (-5775 5950);
DISPLAY INVISIBLE (-5775 5950);
FORCEPROP 1 LAST HDL_TAP TRUE
J 2
(-6100 5775);
DISPLAY 0.872340 (-6100 5775);
DISPLAY INVISIBLE (-6100 5775);
FORCEPROP 1 LAST PATH I253
J 2
(-5773 5900);
DISPLAY 0.872340 (-5773 5900);
PAINT GREEN (-5773 5900);
DISPLAY INVISIBLE (-5773 5900);
FORCEADD TAP..1
R 2
(-5775 5800);
FORCEPROP 3 LASTPIN (-5725 5800) SIG_NAME M_K_CPU0_SA_DQS_DN<1>
J 0
(-5715 5810);
DISPLAY 0.659574 (-5715 5810);
PAINT MONO (-5715 5810);
DISPLAY INVISIBLE (-5715 5810);
FORCEPROP 1 LASTPIN (-5725 5800) BN 1
J 2
(-5713 5808);
DISPLAY 0.489362 (-5713 5808);
PAINT GREEN (-5713 5808);
FORCEPROP 2 LAST CDS_LIB mstr_standard
J 2
(-5775 5800);
DISPLAY 0.723404 (-5775 5800);
PAINT MONO (-5775 5800);
DISPLAY INVISIBLE (-5775 5800);
FORCEPROP 1 LAST BODY_TYPE PLUMBING
J 2
(-5775 5850);
DISPLAY 0.872340 (-5775 5850);
PAINT GREEN (-5775 5850);
DISPLAY INVISIBLE (-5775 5850);
FORCEPROP 1 LAST HDL_TAP TRUE
J 2
(-6100 5675);
DISPLAY 0.872340 (-6100 5675);
DISPLAY INVISIBLE (-6100 5675);
FORCEPROP 1 LAST PATH I254
J 2
(-5773 5800);
DISPLAY 0.872340 (-5773 5800);
PAINT GREEN (-5773 5800);
DISPLAY INVISIBLE (-5773 5800);
FORCEADD TAP..1
R 2
(-5775 5700);
FORCEPROP 3 LASTPIN (-5725 5700) SIG_NAME M_K_CPU0_SA_DQS_DN<2>
J 0
(-5715 5710);
DISPLAY 0.659574 (-5715 5710);
PAINT MONO (-5715 5710);
DISPLAY INVISIBLE (-5715 5710);
FORCEPROP 1 LASTPIN (-5725 5700) BN 2
J 2
(-5713 5708);
DISPLAY 0.489362 (-5713 5708);
PAINT GREEN (-5713 5708);
FORCEPROP 2 LAST CDS_LIB mstr_standard
J 2
(-5775 5700);
DISPLAY 0.723404 (-5775 5700);
PAINT MONO (-5775 5700);
DISPLAY INVISIBLE (-5775 5700);
FORCEPROP 1 LAST BODY_TYPE PLUMBING
J 2
(-5775 5750);
DISPLAY 0.872340 (-5775 5750);
PAINT GREEN (-5775 5750);
DISPLAY INVISIBLE (-5775 5750);
FORCEPROP 1 LAST HDL_TAP TRUE
J 2
(-6100 5575);
DISPLAY 0.872340 (-6100 5575);
DISPLAY INVISIBLE (-6100 5575);
FORCEPROP 1 LAST PATH I255
J 2
(-5773 5700);
DISPLAY 0.872340 (-5773 5700);
PAINT GREEN (-5773 5700);
DISPLAY INVISIBLE (-5773 5700);
FORCEADD TAP..1
R 2
(-5775 5600);
FORCEPROP 3 LASTPIN (-5725 5600) SIG_NAME M_K_CPU0_SA_DQS_DN<3>
J 0
(-5715 5610);
DISPLAY 0.659574 (-5715 5610);
PAINT MONO (-5715 5610);
DISPLAY INVISIBLE (-5715 5610);
FORCEPROP 1 LASTPIN (-5725 5600) BN 3
J 2
(-5713 5608);
DISPLAY 0.489362 (-5713 5608);
PAINT GREEN (-5713 5608);
FORCEPROP 2 LAST CDS_LIB mstr_standard
J 2
(-5775 5600);
DISPLAY 0.723404 (-5775 5600);
PAINT MONO (-5775 5600);
DISPLAY INVISIBLE (-5775 5600);
FORCEPROP 1 LAST BODY_TYPE PLUMBING
J 2
(-5775 5650);
DISPLAY 0.872340 (-5775 5650);
PAINT GREEN (-5775 5650);
DISPLAY INVISIBLE (-5775 5650);
FORCEPROP 1 LAST HDL_TAP TRUE
J 2
(-6100 5475);
DISPLAY 0.872340 (-6100 5475);
DISPLAY INVISIBLE (-6100 5475);
FORCEPROP 1 LAST PATH I256
J 2
(-5773 5600);
DISPLAY 0.872340 (-5773 5600);
PAINT GREEN (-5773 5600);
DISPLAY INVISIBLE (-5773 5600);
FORCEADD TAP..1
R 2
(-5775 5400);
FORCEPROP 3 LASTPIN (-5725 5400) SIG_NAME M_K_CPU0_SA_DQS_DN<5>
J 0
(-5715 5410);
DISPLAY 0.659574 (-5715 5410);
PAINT MONO (-5715 5410);
DISPLAY INVISIBLE (-5715 5410);
FORCEPROP 1 LASTPIN (-5725 5400) BN 5
J 2
(-5713 5408);
DISPLAY 0.489362 (-5713 5408);
PAINT GREEN (-5713 5408);
FORCEPROP 2 LAST CDS_LIB mstr_standard
J 2
(-5775 5400);
DISPLAY 0.723404 (-5775 5400);
PAINT MONO (-5775 5400);
DISPLAY INVISIBLE (-5775 5400);
FORCEPROP 1 LAST BODY_TYPE PLUMBING
J 2
(-5775 5450);
DISPLAY 0.872340 (-5775 5450);
PAINT GREEN (-5775 5450);
DISPLAY INVISIBLE (-5775 5450);
FORCEPROP 1 LAST HDL_TAP TRUE
J 2
(-6100 5275);
DISPLAY 0.872340 (-6100 5275);
DISPLAY INVISIBLE (-6100 5275);
FORCEPROP 1 LAST PATH I257
J 2
(-5773 5400);
DISPLAY 0.872340 (-5773 5400);
PAINT GREEN (-5773 5400);
DISPLAY INVISIBLE (-5773 5400);
FORCEADD TAP..1
R 2
(-5775 5500);
FORCEPROP 3 LASTPIN (-5725 5500) SIG_NAME M_K_CPU0_SA_DQS_DN<4>
J 0
(-5715 5510);
DISPLAY 0.659574 (-5715 5510);
PAINT MONO (-5715 5510);
DISPLAY INVISIBLE (-5715 5510);
FORCEPROP 1 LASTPIN (-5725 5500) BN 4
J 2
(-5713 5508);
DISPLAY 0.489362 (-5713 5508);
PAINT GREEN (-5713 5508);
FORCEPROP 2 LAST CDS_LIB mstr_standard
J 2
(-5775 5500);
DISPLAY 0.723404 (-5775 5500);
PAINT MONO (-5775 5500);
DISPLAY INVISIBLE (-5775 5500);
FORCEPROP 1 LAST BODY_TYPE PLUMBING
J 2
(-5775 5550);
DISPLAY 0.872340 (-5775 5550);
PAINT GREEN (-5775 5550);
DISPLAY INVISIBLE (-5775 5550);
FORCEPROP 1 LAST HDL_TAP TRUE
J 2
(-6100 5375);
DISPLAY 0.872340 (-6100 5375);
DISPLAY INVISIBLE (-6100 5375);
FORCEPROP 1 LAST PATH I258
J 2
(-5773 5500);
DISPLAY 0.872340 (-5773 5500);
PAINT GREEN (-5773 5500);
DISPLAY INVISIBLE (-5773 5500);
FORCEADD TAP..1
R 2
(-5775 5300);
FORCEPROP 3 LASTPIN (-5725 5300) SIG_NAME M_K_CPU0_SA_DQS_DN<6>
J 0
(-5715 5310);
DISPLAY 0.659574 (-5715 5310);
PAINT MONO (-5715 5310);
DISPLAY INVISIBLE (-5715 5310);
FORCEPROP 1 LASTPIN (-5725 5300) BN 6
J 2
(-5713 5308);
DISPLAY 0.489362 (-5713 5308);
PAINT GREEN (-5713 5308);
FORCEPROP 2 LAST CDS_LIB mstr_standard
J 2
(-5775 5300);
DISPLAY 0.723404 (-5775 5300);
PAINT MONO (-5775 5300);
DISPLAY INVISIBLE (-5775 5300);
FORCEPROP 1 LAST BODY_TYPE PLUMBING
J 2
(-5775 5350);
DISPLAY 0.872340 (-5775 5350);
PAINT GREEN (-5775 5350);
DISPLAY INVISIBLE (-5775 5350);
FORCEPROP 1 LAST HDL_TAP TRUE
J 2
(-6100 5175);
DISPLAY 0.872340 (-6100 5175);
DISPLAY INVISIBLE (-6100 5175);
FORCEPROP 1 LAST PATH I259
J 2
(-5773 5300);
DISPLAY 0.872340 (-5773 5300);
PAINT GREEN (-5773 5300);
DISPLAY INVISIBLE (-5773 5300);
FORCEADD TAP..1
R 2
(-5775 5200);
FORCEPROP 3 LASTPIN (-5725 5200) SIG_NAME M_K_CPU0_SA_DQS_DN<7>
J 0
(-5715 5210);
DISPLAY 0.659574 (-5715 5210);
PAINT MONO (-5715 5210);
DISPLAY INVISIBLE (-5715 5210);
FORCEPROP 1 LASTPIN (-5725 5200) BN 7
J 2
(-5713 5208);
DISPLAY 0.489362 (-5713 5208);
PAINT GREEN (-5713 5208);
FORCEPROP 2 LAST CDS_LIB mstr_standard
J 2
(-5775 5200);
DISPLAY 0.723404 (-5775 5200);
PAINT MONO (-5775 5200);
DISPLAY INVISIBLE (-5775 5200);
FORCEPROP 1 LAST BODY_TYPE PLUMBING
J 2
(-5775 5250);
DISPLAY 0.872340 (-5775 5250);
PAINT GREEN (-5775 5250);
DISPLAY INVISIBLE (-5775 5250);
FORCEPROP 1 LAST HDL_TAP TRUE
J 2
(-6100 5075);
DISPLAY 0.872340 (-6100 5075);
DISPLAY INVISIBLE (-6100 5075);
FORCEPROP 1 LAST PATH I260
J 2
(-5773 5200);
DISPLAY 0.872340 (-5773 5200);
PAINT GREEN (-5773 5200);
DISPLAY INVISIBLE (-5773 5200);
FORCEADD TAP..1
R 2
(-5575 4900);
FORCEPROP 3 LASTPIN (-5525 4900) SIG_NAME M_K_CPU0_SB_DQS_DP<0>
J 0
(-5515 4910);
DISPLAY 0.659574 (-5515 4910);
PAINT MONO (-5515 4910);
DISPLAY INVISIBLE (-5515 4910);
FORCEPROP 1 LASTPIN (-5525 4900) BN 0
J 2
(-5513 4908);
DISPLAY 0.489362 (-5513 4908);
PAINT GREEN (-5513 4908);
FORCEPROP 2 LAST CDS_LIB mstr_standard
J 2
(-5575 4900);
DISPLAY 0.723404 (-5575 4900);
PAINT MONO (-5575 4900);
DISPLAY INVISIBLE (-5575 4900);
FORCEPROP 1 LAST BODY_TYPE PLUMBING
J 2
(-5575 4950);
DISPLAY 0.872340 (-5575 4950);
PAINT GREEN (-5575 4950);
DISPLAY INVISIBLE (-5575 4950);
FORCEPROP 1 LAST HDL_TAP TRUE
J 2
(-5900 4775);
DISPLAY 0.872340 (-5900 4775);
DISPLAY INVISIBLE (-5900 4775);
FORCEPROP 1 LAST PATH I261
J 2
(-5573 4900);
DISPLAY 0.872340 (-5573 4900);
PAINT GREEN (-5573 4900);
DISPLAY INVISIBLE (-5573 4900);
FORCEADD TAP..1
R 2
(-5575 5050);
FORCEPROP 3 LASTPIN (-5525 5050) SIG_NAME M_K_CPU0_SA_DQS_DP<9>
J 0
(-5515 5060);
DISPLAY 0.659574 (-5515 5060);
PAINT MONO (-5515 5060);
DISPLAY INVISIBLE (-5515 5060);
FORCEPROP 1 LASTPIN (-5525 5050) BN 9
J 2
(-5513 5058);
DISPLAY 0.489362 (-5513 5058);
PAINT GREEN (-5513 5058);
FORCEPROP 2 LAST CDS_LIB mstr_standard
J 2
(-5575 5050);
DISPLAY 0.723404 (-5575 5050);
PAINT MONO (-5575 5050);
DISPLAY INVISIBLE (-5575 5050);
FORCEPROP 1 LAST BODY_TYPE PLUMBING
J 2
(-5575 5100);
DISPLAY 0.872340 (-5575 5100);
PAINT GREEN (-5575 5100);
DISPLAY INVISIBLE (-5575 5100);
FORCEPROP 1 LAST HDL_TAP TRUE
J 2
(-5900 4925);
DISPLAY 0.872340 (-5900 4925);
DISPLAY INVISIBLE (-5900 4925);
FORCEPROP 1 LAST PATH I262
J 2
(-5573 5050);
DISPLAY 0.872340 (-5573 5050);
PAINT GREEN (-5573 5050);
DISPLAY INVISIBLE (-5573 5050);
FORCEADD TAP..1
R 2
(-5575 4800);
FORCEPROP 3 LASTPIN (-5525 4800) SIG_NAME M_K_CPU0_SB_DQS_DP<1>
J 0
(-5515 4810);
DISPLAY 0.659574 (-5515 4810);
PAINT MONO (-5515 4810);
DISPLAY INVISIBLE (-5515 4810);
FORCEPROP 1 LASTPIN (-5525 4800) BN 1
J 2
(-5513 4808);
DISPLAY 0.489362 (-5513 4808);
PAINT GREEN (-5513 4808);
FORCEPROP 2 LAST CDS_LIB mstr_standard
J 2
(-5575 4800);
DISPLAY 0.723404 (-5575 4800);
PAINT MONO (-5575 4800);
DISPLAY INVISIBLE (-5575 4800);
FORCEPROP 1 LAST BODY_TYPE PLUMBING
J 2
(-5575 4850);
DISPLAY 0.872340 (-5575 4850);
PAINT GREEN (-5575 4850);
DISPLAY INVISIBLE (-5575 4850);
FORCEPROP 1 LAST HDL_TAP TRUE
J 2
(-5900 4675);
DISPLAY 0.872340 (-5900 4675);
DISPLAY INVISIBLE (-5900 4675);
FORCEPROP 1 LAST PATH I263
J 2
(-5573 4800);
DISPLAY 0.872340 (-5573 4800);
PAINT GREEN (-5573 4800);
DISPLAY INVISIBLE (-5573 4800);
FORCEADD TAP..1
R 2
(-5575 4700);
FORCEPROP 3 LASTPIN (-5525 4700) SIG_NAME M_K_CPU0_SB_DQS_DP<2>
J 0
(-5515 4710);
DISPLAY 0.659574 (-5515 4710);
PAINT MONO (-5515 4710);
DISPLAY INVISIBLE (-5515 4710);
FORCEPROP 1 LASTPIN (-5525 4700) BN 2
J 2
(-5513 4708);
DISPLAY 0.489362 (-5513 4708);
PAINT GREEN (-5513 4708);
FORCEPROP 2 LAST CDS_LIB mstr_standard
J 2
(-5575 4700);
DISPLAY 0.723404 (-5575 4700);
PAINT MONO (-5575 4700);
DISPLAY INVISIBLE (-5575 4700);
FORCEPROP 1 LAST BODY_TYPE PLUMBING
J 2
(-5575 4750);
DISPLAY 0.872340 (-5575 4750);
PAINT GREEN (-5575 4750);
DISPLAY INVISIBLE (-5575 4750);
FORCEPROP 1 LAST HDL_TAP TRUE
J 2
(-5900 4575);
DISPLAY 0.872340 (-5900 4575);
DISPLAY INVISIBLE (-5900 4575);
FORCEPROP 1 LAST PATH I264
J 2
(-5573 4700);
DISPLAY 0.872340 (-5573 4700);
PAINT GREEN (-5573 4700);
DISPLAY INVISIBLE (-5573 4700);
FORCEADD TAP..1
R 2
(-5575 4600);
FORCEPROP 3 LASTPIN (-5525 4600) SIG_NAME M_K_CPU0_SB_DQS_DP<3>
J 0
(-5515 4610);
DISPLAY 0.659574 (-5515 4610);
PAINT MONO (-5515 4610);
DISPLAY INVISIBLE (-5515 4610);
FORCEPROP 1 LASTPIN (-5525 4600) BN 3
J 2
(-5513 4608);
DISPLAY 0.489362 (-5513 4608);
PAINT GREEN (-5513 4608);
FORCEPROP 2 LAST CDS_LIB mstr_standard
J 2
(-5575 4600);
DISPLAY 0.723404 (-5575 4600);
PAINT MONO (-5575 4600);
DISPLAY INVISIBLE (-5575 4600);
FORCEPROP 1 LAST BODY_TYPE PLUMBING
J 2
(-5575 4650);
DISPLAY 0.872340 (-5575 4650);
PAINT GREEN (-5575 4650);
DISPLAY INVISIBLE (-5575 4650);
FORCEPROP 1 LAST HDL_TAP TRUE
J 2
(-5900 4475);
DISPLAY 0.872340 (-5900 4475);
DISPLAY INVISIBLE (-5900 4475);
FORCEPROP 1 LAST PATH I265
J 2
(-5573 4600);
DISPLAY 0.872340 (-5573 4600);
PAINT GREEN (-5573 4600);
DISPLAY INVISIBLE (-5573 4600);
FORCEADD TAP..1
R 2
(-5575 4400);
FORCEPROP 3 LASTPIN (-5525 4400) SIG_NAME M_K_CPU0_SB_DQS_DP<5>
J 0
(-5515 4410);
DISPLAY 0.659574 (-5515 4410);
PAINT MONO (-5515 4410);
DISPLAY INVISIBLE (-5515 4410);
FORCEPROP 1 LASTPIN (-5525 4400) BN 5
J 2
(-5513 4408);
DISPLAY 0.489362 (-5513 4408);
PAINT GREEN (-5513 4408);
FORCEPROP 2 LAST CDS_LIB mstr_standard
J 2
(-5575 4400);
DISPLAY 0.723404 (-5575 4400);
PAINT MONO (-5575 4400);
DISPLAY INVISIBLE (-5575 4400);
FORCEPROP 1 LAST BODY_TYPE PLUMBING
J 2
(-5575 4450);
DISPLAY 0.872340 (-5575 4450);
PAINT GREEN (-5575 4450);
DISPLAY INVISIBLE (-5575 4450);
FORCEPROP 1 LAST HDL_TAP TRUE
J 2
(-5900 4275);
DISPLAY 0.872340 (-5900 4275);
DISPLAY INVISIBLE (-5900 4275);
FORCEPROP 1 LAST PATH I266
J 2
(-5573 4400);
DISPLAY 0.872340 (-5573 4400);
PAINT GREEN (-5573 4400);
DISPLAY INVISIBLE (-5573 4400);
FORCEADD TAP..1
R 2
(-5575 4500);
FORCEPROP 3 LASTPIN (-5525 4500) SIG_NAME M_K_CPU0_SB_DQS_DP<4>
J 0
(-5515 4510);
DISPLAY 0.659574 (-5515 4510);
PAINT MONO (-5515 4510);
DISPLAY INVISIBLE (-5515 4510);
FORCEPROP 1 LASTPIN (-5525 4500) BN 4
J 2
(-5513 4508);
DISPLAY 0.489362 (-5513 4508);
PAINT GREEN (-5513 4508);
FORCEPROP 2 LAST CDS_LIB mstr_standard
J 2
(-5575 4500);
DISPLAY 0.723404 (-5575 4500);
PAINT MONO (-5575 4500);
DISPLAY INVISIBLE (-5575 4500);
FORCEPROP 1 LAST BODY_TYPE PLUMBING
J 2
(-5575 4550);
DISPLAY 0.872340 (-5575 4550);
PAINT GREEN (-5575 4550);
DISPLAY INVISIBLE (-5575 4550);
FORCEPROP 1 LAST HDL_TAP TRUE
J 2
(-5900 4375);
DISPLAY 0.872340 (-5900 4375);
DISPLAY INVISIBLE (-5900 4375);
FORCEPROP 1 LAST PATH I267
J 2
(-5573 4500);
DISPLAY 0.872340 (-5573 4500);
PAINT GREEN (-5573 4500);
DISPLAY INVISIBLE (-5573 4500);
FORCEADD TAP..1
R 2
(-5575 4200);
FORCEPROP 3 LASTPIN (-5525 4200) SIG_NAME M_K_CPU0_SB_DQS_DP<7>
J 0
(-5515 4210);
DISPLAY 0.659574 (-5515 4210);
PAINT MONO (-5515 4210);
DISPLAY INVISIBLE (-5515 4210);
FORCEPROP 1 LASTPIN (-5525 4200) BN 7
J 2
(-5513 4208);
DISPLAY 0.489362 (-5513 4208);
PAINT GREEN (-5513 4208);
FORCEPROP 2 LAST CDS_LIB mstr_standard
J 2
(-5575 4200);
DISPLAY 0.723404 (-5575 4200);
PAINT MONO (-5575 4200);
DISPLAY INVISIBLE (-5575 4200);
FORCEPROP 1 LAST BODY_TYPE PLUMBING
J 2
(-5575 4250);
DISPLAY 0.872340 (-5575 4250);
PAINT GREEN (-5575 4250);
DISPLAY INVISIBLE (-5575 4250);
FORCEPROP 1 LAST HDL_TAP TRUE
J 2
(-5900 4075);
DISPLAY 0.872340 (-5900 4075);
DISPLAY INVISIBLE (-5900 4075);
FORCEPROP 1 LAST PATH I268
J 2
(-5573 4200);
DISPLAY 0.872340 (-5573 4200);
PAINT GREEN (-5573 4200);
DISPLAY INVISIBLE (-5573 4200);
FORCEADD TAP..1
R 2
(-5575 4300);
FORCEPROP 3 LASTPIN (-5525 4300) SIG_NAME M_K_CPU0_SB_DQS_DP<6>
J 0
(-5515 4310);
DISPLAY 0.659574 (-5515 4310);
PAINT MONO (-5515 4310);
DISPLAY INVISIBLE (-5515 4310);
FORCEPROP 1 LASTPIN (-5525 4300) BN 6
J 2
(-5513 4308);
DISPLAY 0.489362 (-5513 4308);
PAINT GREEN (-5513 4308);
FORCEPROP 2 LAST CDS_LIB mstr_standard
J 2
(-5575 4300);
DISPLAY 0.723404 (-5575 4300);
PAINT MONO (-5575 4300);
DISPLAY INVISIBLE (-5575 4300);
FORCEPROP 1 LAST BODY_TYPE PLUMBING
J 2
(-5575 4350);
DISPLAY 0.872340 (-5575 4350);
PAINT GREEN (-5575 4350);
DISPLAY INVISIBLE (-5575 4350);
FORCEPROP 1 LAST HDL_TAP TRUE
J 2
(-5900 4175);
DISPLAY 0.872340 (-5900 4175);
DISPLAY INVISIBLE (-5900 4175);
FORCEPROP 1 LAST PATH I269
J 2
(-5573 4300);
DISPLAY 0.872340 (-5573 4300);
PAINT GREEN (-5573 4300);
DISPLAY INVISIBLE (-5573 4300);
FORCEADD TAP..1
R 2
(-5575 4100);
FORCEPROP 3 LASTPIN (-5525 4100) SIG_NAME M_K_CPU0_SB_DQS_DP<8>
J 0
(-5515 4110);
DISPLAY 0.659574 (-5515 4110);
PAINT MONO (-5515 4110);
DISPLAY INVISIBLE (-5515 4110);
FORCEPROP 1 LASTPIN (-5525 4100) BN 8
J 2
(-5513 4108);
DISPLAY 0.489362 (-5513 4108);
PAINT GREEN (-5513 4108);
FORCEPROP 2 LAST CDS_LIB mstr_standard
J 2
(-5575 4100);
DISPLAY 0.723404 (-5575 4100);
PAINT MONO (-5575 4100);
DISPLAY INVISIBLE (-5575 4100);
FORCEPROP 1 LAST BODY_TYPE PLUMBING
J 2
(-5575 4150);
DISPLAY 0.872340 (-5575 4150);
PAINT GREEN (-5575 4150);
DISPLAY INVISIBLE (-5575 4150);
FORCEPROP 1 LAST HDL_TAP TRUE
J 2
(-5900 3975);
DISPLAY 0.872340 (-5900 3975);
DISPLAY INVISIBLE (-5900 3975);
FORCEPROP 1 LAST PATH I270
J 2
(-5573 4100);
DISPLAY 0.872340 (-5573 4100);
PAINT GREEN (-5573 4100);
DISPLAY INVISIBLE (-5573 4100);
FORCEADD TAP..1
R 2
(-5775 5100);
FORCEPROP 3 LASTPIN (-5725 5100) SIG_NAME M_K_CPU0_SA_DQS_DN<8>
J 0
(-5715 5110);
DISPLAY 0.659574 (-5715 5110);
PAINT MONO (-5715 5110);
DISPLAY INVISIBLE (-5715 5110);
FORCEPROP 1 LASTPIN (-5725 5100) BN 8
J 2
(-5713 5108);
DISPLAY 0.489362 (-5713 5108);
PAINT GREEN (-5713 5108);
FORCEPROP 2 LAST CDS_LIB mstr_standard
J 2
(-5775 5100);
DISPLAY 0.723404 (-5775 5100);
PAINT MONO (-5775 5100);
DISPLAY INVISIBLE (-5775 5100);
FORCEPROP 1 LAST BODY_TYPE PLUMBING
J 2
(-5775 5150);
DISPLAY 0.872340 (-5775 5150);
PAINT GREEN (-5775 5150);
DISPLAY INVISIBLE (-5775 5150);
FORCEPROP 1 LAST HDL_TAP TRUE
J 2
(-6100 4975);
DISPLAY 0.872340 (-6100 4975);
DISPLAY INVISIBLE (-6100 4975);
FORCEPROP 1 LAST PATH I271
J 2
(-5773 5100);
DISPLAY 0.872340 (-5773 5100);
PAINT GREEN (-5773 5100);
DISPLAY INVISIBLE (-5773 5100);
FORCEADD TAP..1
R 2
(-5775 5000);
FORCEPROP 3 LASTPIN (-5725 5000) SIG_NAME M_K_CPU0_SA_DQS_DN<9>
J 0
(-5715 5010);
DISPLAY 0.659574 (-5715 5010);
PAINT MONO (-5715 5010);
DISPLAY INVISIBLE (-5715 5010);
FORCEPROP 1 LASTPIN (-5725 5000) BN 9
J 2
(-5713 5008);
DISPLAY 0.489362 (-5713 5008);
PAINT GREEN (-5713 5008);
FORCEPROP 2 LAST CDS_LIB mstr_standard
J 2
(-5775 5000);
DISPLAY 0.723404 (-5775 5000);
PAINT MONO (-5775 5000);
DISPLAY INVISIBLE (-5775 5000);
FORCEPROP 1 LAST BODY_TYPE PLUMBING
J 2
(-5775 5050);
DISPLAY 0.872340 (-5775 5050);
PAINT GREEN (-5775 5050);
DISPLAY INVISIBLE (-5775 5050);
FORCEPROP 1 LAST HDL_TAP TRUE
J 2
(-6100 4875);
DISPLAY 0.872340 (-6100 4875);
DISPLAY INVISIBLE (-6100 4875);
FORCEPROP 1 LAST PATH I272
J 2
(-5773 5000);
DISPLAY 0.872340 (-5773 5000);
PAINT GREEN (-5773 5000);
DISPLAY INVISIBLE (-5773 5000);
FORCEADD TAP..1
R 2
(-5775 4850);
FORCEPROP 3 LASTPIN (-5725 4850) SIG_NAME M_K_CPU0_SB_DQS_DN<0>
J 0
(-5715 4860);
DISPLAY 0.659574 (-5715 4860);
PAINT MONO (-5715 4860);
DISPLAY INVISIBLE (-5715 4860);
FORCEPROP 1 LASTPIN (-5725 4850) BN 0
J 2
(-5713 4858);
DISPLAY 0.489362 (-5713 4858);
PAINT GREEN (-5713 4858);
FORCEPROP 2 LAST CDS_LIB mstr_standard
J 2
(-5775 4850);
DISPLAY 0.723404 (-5775 4850);
PAINT MONO (-5775 4850);
DISPLAY INVISIBLE (-5775 4850);
FORCEPROP 1 LAST BODY_TYPE PLUMBING
J 2
(-5775 4900);
DISPLAY 0.872340 (-5775 4900);
PAINT GREEN (-5775 4900);
DISPLAY INVISIBLE (-5775 4900);
FORCEPROP 1 LAST HDL_TAP TRUE
J 2
(-6100 4725);
DISPLAY 0.872340 (-6100 4725);
DISPLAY INVISIBLE (-6100 4725);
FORCEPROP 1 LAST PATH I273
J 2
(-5773 4850);
DISPLAY 0.872340 (-5773 4850);
PAINT GREEN (-5773 4850);
DISPLAY INVISIBLE (-5773 4850);
FORCEADD TAP..1
R 2
(-5775 4750);
FORCEPROP 3 LASTPIN (-5725 4750) SIG_NAME M_K_CPU0_SB_DQS_DN<1>
J 0
(-5715 4760);
DISPLAY 0.659574 (-5715 4760);
PAINT MONO (-5715 4760);
DISPLAY INVISIBLE (-5715 4760);
FORCEPROP 1 LASTPIN (-5725 4750) BN 1
J 2
(-5713 4758);
DISPLAY 0.489362 (-5713 4758);
PAINT GREEN (-5713 4758);
FORCEPROP 2 LAST CDS_LIB mstr_standard
J 2
(-5775 4750);
DISPLAY 0.723404 (-5775 4750);
PAINT MONO (-5775 4750);
DISPLAY INVISIBLE (-5775 4750);
FORCEPROP 1 LAST BODY_TYPE PLUMBING
J 2
(-5775 4800);
DISPLAY 0.872340 (-5775 4800);
PAINT GREEN (-5775 4800);
DISPLAY INVISIBLE (-5775 4800);
FORCEPROP 1 LAST HDL_TAP TRUE
J 2
(-6100 4625);
DISPLAY 0.872340 (-6100 4625);
DISPLAY INVISIBLE (-6100 4625);
FORCEPROP 1 LAST PATH I274
J 2
(-5773 4750);
DISPLAY 0.872340 (-5773 4750);
PAINT GREEN (-5773 4750);
DISPLAY INVISIBLE (-5773 4750);
FORCEADD TAP..1
R 2
(-5775 4650);
FORCEPROP 3 LASTPIN (-5725 4650) SIG_NAME M_K_CPU0_SB_DQS_DN<2>
J 0
(-5715 4660);
DISPLAY 0.659574 (-5715 4660);
PAINT MONO (-5715 4660);
DISPLAY INVISIBLE (-5715 4660);
FORCEPROP 1 LASTPIN (-5725 4650) BN 2
J 2
(-5713 4658);
DISPLAY 0.489362 (-5713 4658);
PAINT GREEN (-5713 4658);
FORCEPROP 2 LAST CDS_LIB mstr_standard
J 2
(-5775 4650);
DISPLAY 0.723404 (-5775 4650);
PAINT MONO (-5775 4650);
DISPLAY INVISIBLE (-5775 4650);
FORCEPROP 1 LAST BODY_TYPE PLUMBING
J 2
(-5775 4700);
DISPLAY 0.872340 (-5775 4700);
PAINT GREEN (-5775 4700);
DISPLAY INVISIBLE (-5775 4700);
FORCEPROP 1 LAST HDL_TAP TRUE
J 2
(-6100 4525);
DISPLAY 0.872340 (-6100 4525);
DISPLAY INVISIBLE (-6100 4525);
FORCEPROP 1 LAST PATH I275
J 2
(-5773 4650);
DISPLAY 0.872340 (-5773 4650);
PAINT GREEN (-5773 4650);
DISPLAY INVISIBLE (-5773 4650);
FORCEADD TAP..1
R 2
(-5775 4550);
FORCEPROP 3 LASTPIN (-5725 4550) SIG_NAME M_K_CPU0_SB_DQS_DN<3>
J 0
(-5715 4560);
DISPLAY 0.659574 (-5715 4560);
PAINT MONO (-5715 4560);
DISPLAY INVISIBLE (-5715 4560);
FORCEPROP 1 LASTPIN (-5725 4550) BN 3
J 2
(-5713 4558);
DISPLAY 0.489362 (-5713 4558);
PAINT GREEN (-5713 4558);
FORCEPROP 2 LAST CDS_LIB mstr_standard
J 2
(-5775 4550);
DISPLAY 0.723404 (-5775 4550);
PAINT MONO (-5775 4550);
DISPLAY INVISIBLE (-5775 4550);
FORCEPROP 1 LAST BODY_TYPE PLUMBING
J 2
(-5775 4600);
DISPLAY 0.872340 (-5775 4600);
PAINT GREEN (-5775 4600);
DISPLAY INVISIBLE (-5775 4600);
FORCEPROP 1 LAST HDL_TAP TRUE
J 2
(-6100 4425);
DISPLAY 0.872340 (-6100 4425);
DISPLAY INVISIBLE (-6100 4425);
FORCEPROP 1 LAST PATH I276
J 2
(-5773 4550);
DISPLAY 0.872340 (-5773 4550);
PAINT GREEN (-5773 4550);
DISPLAY INVISIBLE (-5773 4550);
FORCEADD TAP..1
R 2
(-5775 4450);
FORCEPROP 3 LASTPIN (-5725 4450) SIG_NAME M_K_CPU0_SB_DQS_DN<4>
J 0
(-5715 4460);
DISPLAY 0.659574 (-5715 4460);
PAINT MONO (-5715 4460);
DISPLAY INVISIBLE (-5715 4460);
FORCEPROP 1 LASTPIN (-5725 4450) BN 4
J 2
(-5713 4458);
DISPLAY 0.489362 (-5713 4458);
PAINT GREEN (-5713 4458);
FORCEPROP 2 LAST CDS_LIB mstr_standard
J 2
(-5775 4450);
DISPLAY 0.723404 (-5775 4450);
PAINT MONO (-5775 4450);
DISPLAY INVISIBLE (-5775 4450);
FORCEPROP 1 LAST BODY_TYPE PLUMBING
J 2
(-5775 4500);
DISPLAY 0.872340 (-5775 4500);
PAINT GREEN (-5775 4500);
DISPLAY INVISIBLE (-5775 4500);
FORCEPROP 1 LAST HDL_TAP TRUE
J 2
(-6100 4325);
DISPLAY 0.872340 (-6100 4325);
DISPLAY INVISIBLE (-6100 4325);
FORCEPROP 1 LAST PATH I277
J 2
(-5773 4450);
DISPLAY 0.872340 (-5773 4450);
PAINT GREEN (-5773 4450);
DISPLAY INVISIBLE (-5773 4450);
FORCEADD TAP..1
R 2
(-5775 4250);
FORCEPROP 3 LASTPIN (-5725 4250) SIG_NAME M_K_CPU0_SB_DQS_DN<6>
J 0
(-5715 4260);
DISPLAY 0.659574 (-5715 4260);
PAINT MONO (-5715 4260);
DISPLAY INVISIBLE (-5715 4260);
FORCEPROP 1 LASTPIN (-5725 4250) BN 6
J 2
(-5713 4258);
DISPLAY 0.489362 (-5713 4258);
PAINT GREEN (-5713 4258);
FORCEPROP 2 LAST CDS_LIB mstr_standard
J 2
(-5775 4250);
DISPLAY 0.723404 (-5775 4250);
PAINT MONO (-5775 4250);
DISPLAY INVISIBLE (-5775 4250);
FORCEPROP 1 LAST BODY_TYPE PLUMBING
J 2
(-5775 4300);
DISPLAY 0.872340 (-5775 4300);
PAINT GREEN (-5775 4300);
DISPLAY INVISIBLE (-5775 4300);
FORCEPROP 1 LAST HDL_TAP TRUE
J 2
(-6100 4125);
DISPLAY 0.872340 (-6100 4125);
DISPLAY INVISIBLE (-6100 4125);
FORCEPROP 1 LAST PATH I278
J 2
(-5773 4250);
DISPLAY 0.872340 (-5773 4250);
PAINT GREEN (-5773 4250);
DISPLAY INVISIBLE (-5773 4250);
FORCEADD TAP..1
R 2
(-5775 4350);
FORCEPROP 3 LASTPIN (-5725 4350) SIG_NAME M_K_CPU0_SB_DQS_DN<5>
J 0
(-5715 4360);
DISPLAY 0.659574 (-5715 4360);
PAINT MONO (-5715 4360);
DISPLAY INVISIBLE (-5715 4360);
FORCEPROP 1 LASTPIN (-5725 4350) BN 5
J 2
(-5713 4358);
DISPLAY 0.489362 (-5713 4358);
PAINT GREEN (-5713 4358);
FORCEPROP 2 LAST CDS_LIB mstr_standard
J 2
(-5775 4350);
DISPLAY 0.723404 (-5775 4350);
PAINT MONO (-5775 4350);
DISPLAY INVISIBLE (-5775 4350);
FORCEPROP 1 LAST BODY_TYPE PLUMBING
J 2
(-5775 4400);
DISPLAY 0.872340 (-5775 4400);
PAINT GREEN (-5775 4400);
DISPLAY INVISIBLE (-5775 4400);
FORCEPROP 1 LAST HDL_TAP TRUE
J 2
(-6100 4225);
DISPLAY 0.872340 (-6100 4225);
DISPLAY INVISIBLE (-6100 4225);
FORCEPROP 1 LAST PATH I279
J 2
(-5773 4350);
DISPLAY 0.872340 (-5773 4350);
PAINT GREEN (-5773 4350);
DISPLAY INVISIBLE (-5773 4350);
FORCEADD TAP..1
R 2
(-5775 4150);
FORCEPROP 3 LASTPIN (-5725 4150) SIG_NAME M_K_CPU0_SB_DQS_DN<7>
J 0
(-5715 4160);
DISPLAY 0.659574 (-5715 4160);
PAINT MONO (-5715 4160);
DISPLAY INVISIBLE (-5715 4160);
FORCEPROP 1 LASTPIN (-5725 4150) BN 7
J 2
(-5713 4158);
DISPLAY 0.489362 (-5713 4158);
PAINT GREEN (-5713 4158);
FORCEPROP 2 LAST CDS_LIB mstr_standard
J 2
(-5775 4150);
DISPLAY 0.723404 (-5775 4150);
PAINT MONO (-5775 4150);
DISPLAY INVISIBLE (-5775 4150);
FORCEPROP 1 LAST BODY_TYPE PLUMBING
J 2
(-5775 4200);
DISPLAY 0.872340 (-5775 4200);
PAINT GREEN (-5775 4200);
DISPLAY INVISIBLE (-5775 4200);
FORCEPROP 1 LAST HDL_TAP TRUE
J 2
(-6100 4025);
DISPLAY 0.872340 (-6100 4025);
DISPLAY INVISIBLE (-6100 4025);
FORCEPROP 1 LAST PATH I280
J 2
(-5773 4150);
DISPLAY 0.872340 (-5773 4150);
PAINT GREEN (-5773 4150);
DISPLAY INVISIBLE (-5773 4150);
FORCEADD OFFPAGE..3
R 2
(-6475 5925);
FORCEPROP 2 LAST $XR0 96 
J 0
(-6754 5925);
DISPLAY 0.638298 (-6754 5925);
PAINT MONO (-6754 5925);
FORCEPROP 2 LAST CDS_LIB standard
J 0
(-6475 5925);
DISPLAY INVISIBLE (-6475 5925);
FORCEPROP 1 LAST OFFPAGE TRUE
J 2
(-6800 5800);
DISPLAY 0.872340 (-6800 5800);
PAINT GREEN (-6800 5800);
DISPLAY INVISIBLE (-6800 5800);
FORCEPROP 1 LAST COMMENT_BODY TRUE
J 2
(-6425 5825);
DISPLAY 0.872340 (-6425 5825);
PAINT GREEN (-6425 5825);
DISPLAY INVISIBLE (-6425 5825);
FORCEPROP 2 LAST PATH I281
J 0
(-6775 5975);
DISPLAY 1.021277 (-6775 5975);
DISPLAY INVISIBLE (-6775 5975);
FORCEADD OFFPAGE..3
R 2
(-6475 5975);
FORCEPROP 2 LAST $XR0 96 
J 0
(-6754 5975);
DISPLAY 0.638298 (-6754 5975);
PAINT MONO (-6754 5975);
FORCEPROP 2 LAST CDS_LIB standard
J 0
(-6475 5975);
DISPLAY INVISIBLE (-6475 5975);
FORCEPROP 1 LAST OFFPAGE TRUE
J 2
(-6800 5850);
DISPLAY 0.872340 (-6800 5850);
PAINT GREEN (-6800 5850);
DISPLAY INVISIBLE (-6800 5850);
FORCEPROP 1 LAST COMMENT_BODY TRUE
J 2
(-6425 5875);
DISPLAY 0.872340 (-6425 5875);
PAINT GREEN (-6425 5875);
DISPLAY INVISIBLE (-6425 5875);
FORCEPROP 2 LAST PATH I282
J 0
(-6775 6025);
DISPLAY 1.021277 (-6775 6025);
DISPLAY INVISIBLE (-6775 6025);
FORCEADD OFFPAGE..3
R 2
(-6475 4925);
FORCEPROP 2 LAST $XR0 96 
J 0
(-6754 4925);
DISPLAY 0.638298 (-6754 4925);
PAINT MONO (-6754 4925);
FORCEPROP 2 LAST CDS_LIB standard
J 0
(-6475 4925);
DISPLAY INVISIBLE (-6475 4925);
FORCEPROP 1 LAST OFFPAGE TRUE
J 2
(-6800 4800);
DISPLAY 0.872340 (-6800 4800);
PAINT GREEN (-6800 4800);
DISPLAY INVISIBLE (-6800 4800);
FORCEPROP 1 LAST COMMENT_BODY TRUE
J 2
(-6425 4825);
DISPLAY 0.872340 (-6425 4825);
PAINT GREEN (-6425 4825);
DISPLAY INVISIBLE (-6425 4825);
FORCEPROP 2 LAST PATH I283
J 0
(-6775 4975);
DISPLAY 1.021277 (-6775 4975);
DISPLAY INVISIBLE (-6775 4975);
FORCEADD OFFPAGE..3
R 2
(-6475 4875);
FORCEPROP 2 LAST $XR0 96 
J 0
(-6754 4875);
DISPLAY 0.638298 (-6754 4875);
PAINT MONO (-6754 4875);
FORCEPROP 2 LAST CDS_LIB standard
J 0
(-6475 4875);
DISPLAY INVISIBLE (-6475 4875);
FORCEPROP 1 LAST OFFPAGE TRUE
J 2
(-6800 4750);
DISPLAY 0.872340 (-6800 4750);
PAINT GREEN (-6800 4750);
DISPLAY INVISIBLE (-6800 4750);
FORCEPROP 1 LAST COMMENT_BODY TRUE
J 2
(-6425 4775);
DISPLAY 0.872340 (-6425 4775);
PAINT GREEN (-6425 4775);
DISPLAY INVISIBLE (-6425 4775);
FORCEPROP 2 LAST PATH I284
J 0
(-6775 4925);
DISPLAY 1.021277 (-6775 4925);
DISPLAY INVISIBLE (-6775 4925);
FORCEADD TAP..1
R 2
(-5575 4000);
FORCEPROP 3 LASTPIN (-5525 4000) SIG_NAME M_K_CPU0_SB_DQS_DP<9>
J 0
(-5515 4010);
DISPLAY 0.659574 (-5515 4010);
PAINT MONO (-5515 4010);
DISPLAY INVISIBLE (-5515 4010);
FORCEPROP 1 LASTPIN (-5525 4000) BN 9
J 2
(-5513 4008);
DISPLAY 0.489362 (-5513 4008);
PAINT GREEN (-5513 4008);
FORCEPROP 2 LAST CDS_LIB mstr_standard
J 2
(-5575 4000);
DISPLAY 0.723404 (-5575 4000);
PAINT MONO (-5575 4000);
DISPLAY INVISIBLE (-5575 4000);
FORCEPROP 1 LAST BODY_TYPE PLUMBING
J 2
(-5575 4050);
DISPLAY 0.872340 (-5575 4050);
PAINT GREEN (-5575 4050);
DISPLAY INVISIBLE (-5575 4050);
FORCEPROP 1 LAST HDL_TAP TRUE
J 2
(-5900 3875);
DISPLAY 0.872340 (-5900 3875);
DISPLAY INVISIBLE (-5900 3875);
FORCEPROP 1 LAST PATH I285
J 2
(-5573 4000);
DISPLAY 0.872340 (-5573 4000);
PAINT GREEN (-5573 4000);
DISPLAY INVISIBLE (-5573 4000);
FORCEADD TAP..1
R 2
(-5775 4050);
FORCEPROP 3 LASTPIN (-5725 4050) SIG_NAME M_K_CPU0_SB_DQS_DN<8>
J 0
(-5715 4060);
DISPLAY 0.659574 (-5715 4060);
PAINT MONO (-5715 4060);
DISPLAY INVISIBLE (-5715 4060);
FORCEPROP 1 LASTPIN (-5725 4050) BN 8
J 2
(-5713 4058);
DISPLAY 0.489362 (-5713 4058);
PAINT GREEN (-5713 4058);
FORCEPROP 2 LAST CDS_LIB mstr_standard
J 2
(-5775 4050);
DISPLAY 0.723404 (-5775 4050);
PAINT MONO (-5775 4050);
DISPLAY INVISIBLE (-5775 4050);
FORCEPROP 1 LAST BODY_TYPE PLUMBING
J 2
(-5775 4100);
DISPLAY 0.872340 (-5775 4100);
PAINT GREEN (-5775 4100);
DISPLAY INVISIBLE (-5775 4100);
FORCEPROP 1 LAST HDL_TAP TRUE
J 2
(-6100 3925);
DISPLAY 0.872340 (-6100 3925);
DISPLAY INVISIBLE (-6100 3925);
FORCEPROP 1 LAST PATH I286
J 2
(-5773 4050);
DISPLAY 0.872340 (-5773 4050);
PAINT GREEN (-5773 4050);
DISPLAY INVISIBLE (-5773 4050);
FORCEADD TAP..1
R 2
(-5775 3950);
FORCEPROP 3 LASTPIN (-5725 3950) SIG_NAME M_K_CPU0_SB_DQS_DN<9>
J 0
(-5715 3960);
DISPLAY 0.659574 (-5715 3960);
PAINT MONO (-5715 3960);
DISPLAY INVISIBLE (-5715 3960);
FORCEPROP 1 LASTPIN (-5725 3950) BN 9
J 2
(-5713 3958);
DISPLAY 0.489362 (-5713 3958);
PAINT GREEN (-5713 3958);
FORCEPROP 2 LAST CDS_LIB mstr_standard
J 2
(-5775 3950);
DISPLAY 0.723404 (-5775 3950);
PAINT MONO (-5775 3950);
DISPLAY INVISIBLE (-5775 3950);
FORCEPROP 1 LAST BODY_TYPE PLUMBING
J 2
(-5775 4000);
DISPLAY 0.872340 (-5775 4000);
PAINT GREEN (-5775 4000);
DISPLAY INVISIBLE (-5775 4000);
FORCEPROP 1 LAST HDL_TAP TRUE
J 2
(-6100 3825);
DISPLAY 0.872340 (-6100 3825);
DISPLAY INVISIBLE (-6100 3825);
FORCEPROP 1 LAST PATH I287
J 2
(-5773 3950);
DISPLAY 0.872340 (-5773 3950);
PAINT GREEN (-5773 3950);
DISPLAY INVISIBLE (-5773 3950);
FORCEADD TAP..1
R 2
(-5775 3800);
FORCEPROP 3 LASTPIN (-5725 3800) SIG_NAME M_K_CPU0_SA_CA<0>
J 0
(-5715 3810);
DISPLAY 0.659574 (-5715 3810);
PAINT MONO (-5715 3810);
DISPLAY INVISIBLE (-5715 3810);
FORCEPROP 1 LASTPIN (-5725 3800) BN 0
J 2
(-5713 3808);
DISPLAY 0.489362 (-5713 3808);
PAINT GREEN (-5713 3808);
FORCEPROP 2 LAST CDS_LIB mstr_standard
J 0
(-5775 3800);
DISPLAY 0.723404 (-5775 3800);
PAINT MONO (-5775 3800);
DISPLAY INVISIBLE (-5775 3800);
FORCEPROP 1 LAST BODY_TYPE PLUMBING
J 2
(-5775 3850);
DISPLAY 0.872340 (-5775 3850);
PAINT GREEN (-5775 3850);
DISPLAY INVISIBLE (-5775 3850);
FORCEPROP 1 LAST HDL_TAP TRUE
J 2
(-6100 3675);
DISPLAY 0.872340 (-6100 3675);
DISPLAY INVISIBLE (-6100 3675);
FORCEPROP 1 LAST PATH I288
J 2
(-5773 3800);
DISPLAY 0.872340 (-5773 3800);
PAINT GREEN (-5773 3800);
DISPLAY INVISIBLE (-5773 3800);
FORCEADD TAP..1
R 2
(-5775 3750);
FORCEPROP 3 LASTPIN (-5725 3750) SIG_NAME M_K_CPU0_SA_CA<1>
J 0
(-5715 3760);
DISPLAY 0.659574 (-5715 3760);
PAINT MONO (-5715 3760);
DISPLAY INVISIBLE (-5715 3760);
FORCEPROP 1 LASTPIN (-5725 3750) BN 1
J 2
(-5713 3758);
DISPLAY 0.489362 (-5713 3758);
PAINT GREEN (-5713 3758);
FORCEPROP 2 LAST CDS_LIB mstr_standard
J 0
(-5775 3750);
DISPLAY 0.723404 (-5775 3750);
PAINT MONO (-5775 3750);
DISPLAY INVISIBLE (-5775 3750);
FORCEPROP 1 LAST BODY_TYPE PLUMBING
J 2
(-5775 3800);
DISPLAY 0.872340 (-5775 3800);
PAINT GREEN (-5775 3800);
DISPLAY INVISIBLE (-5775 3800);
FORCEPROP 1 LAST HDL_TAP TRUE
J 2
(-6100 3625);
DISPLAY 0.872340 (-6100 3625);
DISPLAY INVISIBLE (-6100 3625);
FORCEPROP 1 LAST PATH I289
J 2
(-5773 3750);
DISPLAY 0.872340 (-5773 3750);
PAINT GREEN (-5773 3750);
DISPLAY INVISIBLE (-5773 3750);
FORCEADD TAP..1
R 2
(-5775 3700);
FORCEPROP 3 LASTPIN (-5725 3700) SIG_NAME M_K_CPU0_SA_CA<2>
J 0
(-5715 3710);
DISPLAY 0.659574 (-5715 3710);
PAINT MONO (-5715 3710);
DISPLAY INVISIBLE (-5715 3710);
FORCEPROP 1 LASTPIN (-5725 3700) BN 2
J 2
(-5713 3708);
DISPLAY 0.489362 (-5713 3708);
PAINT GREEN (-5713 3708);
FORCEPROP 2 LAST CDS_LIB mstr_standard
J 0
(-5775 3700);
DISPLAY 0.723404 (-5775 3700);
PAINT MONO (-5775 3700);
DISPLAY INVISIBLE (-5775 3700);
FORCEPROP 1 LAST BODY_TYPE PLUMBING
J 2
(-5775 3750);
DISPLAY 0.872340 (-5775 3750);
PAINT GREEN (-5775 3750);
DISPLAY INVISIBLE (-5775 3750);
FORCEPROP 1 LAST HDL_TAP TRUE
J 2
(-6100 3575);
DISPLAY 0.872340 (-6100 3575);
DISPLAY INVISIBLE (-6100 3575);
FORCEPROP 1 LAST PATH I290
J 2
(-5773 3700);
DISPLAY 0.872340 (-5773 3700);
PAINT GREEN (-5773 3700);
DISPLAY INVISIBLE (-5773 3700);
FORCEADD TAP..1
R 2
(-5775 3650);
FORCEPROP 3 LASTPIN (-5725 3650) SIG_NAME M_K_CPU0_SA_CA<3>
J 0
(-5715 3660);
DISPLAY 0.659574 (-5715 3660);
PAINT MONO (-5715 3660);
DISPLAY INVISIBLE (-5715 3660);
FORCEPROP 1 LASTPIN (-5725 3650) BN 3
J 2
(-5713 3658);
DISPLAY 0.489362 (-5713 3658);
PAINT GREEN (-5713 3658);
FORCEPROP 2 LAST CDS_LIB mstr_standard
J 0
(-5775 3650);
DISPLAY 0.723404 (-5775 3650);
PAINT MONO (-5775 3650);
DISPLAY INVISIBLE (-5775 3650);
FORCEPROP 1 LAST BODY_TYPE PLUMBING
J 2
(-5775 3700);
DISPLAY 0.872340 (-5775 3700);
PAINT GREEN (-5775 3700);
DISPLAY INVISIBLE (-5775 3700);
FORCEPROP 1 LAST HDL_TAP TRUE
J 2
(-6100 3525);
DISPLAY 0.872340 (-6100 3525);
DISPLAY INVISIBLE (-6100 3525);
FORCEPROP 1 LAST PATH I291
J 2
(-5773 3650);
DISPLAY 0.872340 (-5773 3650);
PAINT GREEN (-5773 3650);
DISPLAY INVISIBLE (-5773 3650);
FORCEADD TAP..1
R 2
(-5775 3600);
FORCEPROP 3 LASTPIN (-5725 3600) SIG_NAME M_K_CPU0_SA_CA<4>
J 0
(-5715 3610);
DISPLAY 0.659574 (-5715 3610);
PAINT MONO (-5715 3610);
DISPLAY INVISIBLE (-5715 3610);
FORCEPROP 1 LASTPIN (-5725 3600) BN 4
J 2
(-5713 3608);
DISPLAY 0.489362 (-5713 3608);
PAINT GREEN (-5713 3608);
FORCEPROP 2 LAST CDS_LIB mstr_standard
J 0
(-5775 3600);
DISPLAY 0.723404 (-5775 3600);
PAINT MONO (-5775 3600);
DISPLAY INVISIBLE (-5775 3600);
FORCEPROP 1 LAST BODY_TYPE PLUMBING
J 2
(-5775 3650);
DISPLAY 0.872340 (-5775 3650);
PAINT GREEN (-5775 3650);
DISPLAY INVISIBLE (-5775 3650);
FORCEPROP 1 LAST HDL_TAP TRUE
J 2
(-6100 3475);
DISPLAY 0.872340 (-6100 3475);
DISPLAY INVISIBLE (-6100 3475);
FORCEPROP 1 LAST PATH I292
J 2
(-5773 3600);
DISPLAY 0.872340 (-5773 3600);
PAINT GREEN (-5773 3600);
DISPLAY INVISIBLE (-5773 3600);
FORCEADD TAP..1
R 2
(-5775 3500);
FORCEPROP 3 LASTPIN (-5725 3500) SIG_NAME M_K_CPU0_SA_CA<6>
J 0
(-5715 3510);
DISPLAY 0.659574 (-5715 3510);
PAINT MONO (-5715 3510);
DISPLAY INVISIBLE (-5715 3510);
FORCEPROP 1 LASTPIN (-5725 3500) BN 6
J 2
(-5713 3508);
DISPLAY 0.489362 (-5713 3508);
PAINT GREEN (-5713 3508);
FORCEPROP 2 LAST CDS_LIB mstr_standard
J 0
(-5775 3500);
DISPLAY 0.723404 (-5775 3500);
PAINT MONO (-5775 3500);
DISPLAY INVISIBLE (-5775 3500);
FORCEPROP 1 LAST BODY_TYPE PLUMBING
J 2
(-5775 3550);
DISPLAY 0.872340 (-5775 3550);
PAINT GREEN (-5775 3550);
DISPLAY INVISIBLE (-5775 3550);
FORCEPROP 1 LAST HDL_TAP TRUE
J 2
(-6100 3375);
DISPLAY 0.872340 (-6100 3375);
DISPLAY INVISIBLE (-6100 3375);
FORCEPROP 1 LAST PATH I293
J 2
(-5773 3500);
DISPLAY 0.872340 (-5773 3500);
PAINT GREEN (-5773 3500);
DISPLAY INVISIBLE (-5773 3500);
FORCEADD TAP..1
R 2
(-5775 3550);
FORCEPROP 3 LASTPIN (-5725 3550) SIG_NAME M_K_CPU0_SA_CA<5>
J 0
(-5715 3560);
DISPLAY 0.659574 (-5715 3560);
PAINT MONO (-5715 3560);
DISPLAY INVISIBLE (-5715 3560);
FORCEPROP 1 LASTPIN (-5725 3550) BN 5
J 2
(-5713 3558);
DISPLAY 0.489362 (-5713 3558);
PAINT GREEN (-5713 3558);
FORCEPROP 2 LAST CDS_LIB mstr_standard
J 0
(-5775 3550);
DISPLAY 0.723404 (-5775 3550);
PAINT MONO (-5775 3550);
DISPLAY INVISIBLE (-5775 3550);
FORCEPROP 1 LAST BODY_TYPE PLUMBING
J 2
(-5775 3600);
DISPLAY 0.872340 (-5775 3600);
PAINT GREEN (-5775 3600);
DISPLAY INVISIBLE (-5775 3600);
FORCEPROP 1 LAST HDL_TAP TRUE
J 2
(-6100 3425);
DISPLAY 0.872340 (-6100 3425);
DISPLAY INVISIBLE (-6100 3425);
FORCEPROP 1 LAST PATH I294
J 2
(-5773 3550);
DISPLAY 0.872340 (-5773 3550);
PAINT GREEN (-5773 3550);
DISPLAY INVISIBLE (-5773 3550);
FORCEADD TAP..1
R 2
(-5775 3400);
FORCEPROP 3 LASTPIN (-5725 3400) SIG_NAME M_K_CPU0_SB_CA<0>
J 0
(-5715 3410);
DISPLAY 0.659574 (-5715 3410);
PAINT MONO (-5715 3410);
DISPLAY INVISIBLE (-5715 3410);
FORCEPROP 1 LASTPIN (-5725 3400) BN 0
J 2
(-5713 3408);
DISPLAY 0.489362 (-5713 3408);
PAINT GREEN (-5713 3408);
FORCEPROP 2 LAST CDS_LIB mstr_standard
J 0
(-5775 3400);
DISPLAY 0.723404 (-5775 3400);
PAINT MONO (-5775 3400);
DISPLAY INVISIBLE (-5775 3400);
FORCEPROP 1 LAST BODY_TYPE PLUMBING
J 2
(-5775 3450);
DISPLAY 0.872340 (-5775 3450);
PAINT GREEN (-5775 3450);
DISPLAY INVISIBLE (-5775 3450);
FORCEPROP 1 LAST HDL_TAP TRUE
J 2
(-6100 3275);
DISPLAY 0.872340 (-6100 3275);
DISPLAY INVISIBLE (-6100 3275);
FORCEPROP 1 LAST PATH I295
J 2
(-5773 3400);
DISPLAY 0.872340 (-5773 3400);
PAINT GREEN (-5773 3400);
DISPLAY INVISIBLE (-5773 3400);
FORCEADD TAP..1
R 2
(-5775 3350);
FORCEPROP 3 LASTPIN (-5725 3350) SIG_NAME M_K_CPU0_SB_CA<1>
J 0
(-5715 3360);
DISPLAY 0.659574 (-5715 3360);
PAINT MONO (-5715 3360);
DISPLAY INVISIBLE (-5715 3360);
FORCEPROP 1 LASTPIN (-5725 3350) BN 1
J 2
(-5713 3358);
DISPLAY 0.489362 (-5713 3358);
PAINT GREEN (-5713 3358);
FORCEPROP 2 LAST CDS_LIB mstr_standard
J 0
(-5775 3350);
DISPLAY 0.723404 (-5775 3350);
PAINT MONO (-5775 3350);
DISPLAY INVISIBLE (-5775 3350);
FORCEPROP 1 LAST BODY_TYPE PLUMBING
J 2
(-5775 3400);
DISPLAY 0.872340 (-5775 3400);
PAINT GREEN (-5775 3400);
DISPLAY INVISIBLE (-5775 3400);
FORCEPROP 1 LAST HDL_TAP TRUE
J 2
(-6100 3225);
DISPLAY 0.872340 (-6100 3225);
DISPLAY INVISIBLE (-6100 3225);
FORCEPROP 1 LAST PATH I296
J 2
(-5773 3350);
DISPLAY 0.872340 (-5773 3350);
PAINT GREEN (-5773 3350);
DISPLAY INVISIBLE (-5773 3350);
FORCEADD TAP..1
R 2
(-5775 3300);
FORCEPROP 3 LASTPIN (-5725 3300) SIG_NAME M_K_CPU0_SB_CA<2>
J 0
(-5715 3310);
DISPLAY 0.659574 (-5715 3310);
PAINT MONO (-5715 3310);
DISPLAY INVISIBLE (-5715 3310);
FORCEPROP 1 LASTPIN (-5725 3300) BN 2
J 2
(-5713 3308);
DISPLAY 0.489362 (-5713 3308);
PAINT GREEN (-5713 3308);
FORCEPROP 2 LAST CDS_LIB mstr_standard
J 0
(-5775 3300);
DISPLAY 0.723404 (-5775 3300);
PAINT MONO (-5775 3300);
DISPLAY INVISIBLE (-5775 3300);
FORCEPROP 1 LAST BODY_TYPE PLUMBING
J 2
(-5775 3350);
DISPLAY 0.872340 (-5775 3350);
PAINT GREEN (-5775 3350);
DISPLAY INVISIBLE (-5775 3350);
FORCEPROP 1 LAST HDL_TAP TRUE
J 2
(-6100 3175);
DISPLAY 0.872340 (-6100 3175);
DISPLAY INVISIBLE (-6100 3175);
FORCEPROP 1 LAST PATH I297
J 2
(-5773 3300);
DISPLAY 0.872340 (-5773 3300);
PAINT GREEN (-5773 3300);
DISPLAY INVISIBLE (-5773 3300);
FORCEADD TAP..1
R 2
(-5775 3250);
FORCEPROP 3 LASTPIN (-5725 3250) SIG_NAME M_K_CPU0_SB_CA<3>
J 0
(-5715 3260);
DISPLAY 0.659574 (-5715 3260);
PAINT MONO (-5715 3260);
DISPLAY INVISIBLE (-5715 3260);
FORCEPROP 1 LASTPIN (-5725 3250) BN 3
J 2
(-5713 3258);
DISPLAY 0.489362 (-5713 3258);
PAINT GREEN (-5713 3258);
FORCEPROP 2 LAST CDS_LIB mstr_standard
J 0
(-5775 3250);
DISPLAY 0.723404 (-5775 3250);
PAINT MONO (-5775 3250);
DISPLAY INVISIBLE (-5775 3250);
FORCEPROP 1 LAST BODY_TYPE PLUMBING
J 2
(-5775 3300);
DISPLAY 0.872340 (-5775 3300);
PAINT GREEN (-5775 3300);
DISPLAY INVISIBLE (-5775 3300);
FORCEPROP 1 LAST HDL_TAP TRUE
J 2
(-6100 3125);
DISPLAY 0.872340 (-6100 3125);
DISPLAY INVISIBLE (-6100 3125);
FORCEPROP 1 LAST PATH I298
J 2
(-5773 3250);
DISPLAY 0.872340 (-5773 3250);
PAINT GREEN (-5773 3250);
DISPLAY INVISIBLE (-5773 3250);
FORCEADD TAP..1
R 2
(-5775 3200);
FORCEPROP 3 LASTPIN (-5725 3200) SIG_NAME M_K_CPU0_SB_CA<4>
J 0
(-5715 3210);
DISPLAY 0.659574 (-5715 3210);
PAINT MONO (-5715 3210);
DISPLAY INVISIBLE (-5715 3210);
FORCEPROP 1 LASTPIN (-5725 3200) BN 4
J 2
(-5713 3208);
DISPLAY 0.489362 (-5713 3208);
PAINT GREEN (-5713 3208);
FORCEPROP 2 LAST CDS_LIB mstr_standard
J 0
(-5775 3200);
DISPLAY 0.723404 (-5775 3200);
PAINT MONO (-5775 3200);
DISPLAY INVISIBLE (-5775 3200);
FORCEPROP 1 LAST BODY_TYPE PLUMBING
J 2
(-5775 3250);
DISPLAY 0.872340 (-5775 3250);
PAINT GREEN (-5775 3250);
DISPLAY INVISIBLE (-5775 3250);
FORCEPROP 1 LAST HDL_TAP TRUE
J 2
(-6100 3075);
DISPLAY 0.872340 (-6100 3075);
DISPLAY INVISIBLE (-6100 3075);
FORCEPROP 1 LAST PATH I299
J 2
(-5773 3200);
DISPLAY 0.872340 (-5773 3200);
PAINT GREEN (-5773 3200);
DISPLAY INVISIBLE (-5773 3200);
FORCEADD TAP..1
R 2
(-5775 3100);
FORCEPROP 3 LASTPIN (-5725 3100) SIG_NAME M_K_CPU0_SB_CA<6>
J 0
(-5715 3110);
DISPLAY 0.659574 (-5715 3110);
PAINT MONO (-5715 3110);
DISPLAY INVISIBLE (-5715 3110);
FORCEPROP 1 LASTPIN (-5725 3100) BN 6
J 2
(-5713 3108);
DISPLAY 0.489362 (-5713 3108);
PAINT GREEN (-5713 3108);
FORCEPROP 2 LAST CDS_LIB mstr_standard
J 0
(-5775 3100);
DISPLAY 0.723404 (-5775 3100);
PAINT MONO (-5775 3100);
DISPLAY INVISIBLE (-5775 3100);
FORCEPROP 1 LAST BODY_TYPE PLUMBING
J 2
(-5775 3150);
DISPLAY 0.872340 (-5775 3150);
PAINT GREEN (-5775 3150);
DISPLAY INVISIBLE (-5775 3150);
FORCEPROP 1 LAST HDL_TAP TRUE
J 2
(-6100 2975);
DISPLAY 0.872340 (-6100 2975);
DISPLAY INVISIBLE (-6100 2975);
FORCEPROP 1 LAST PATH I300
J 2
(-5773 3100);
DISPLAY 0.872340 (-5773 3100);
PAINT GREEN (-5773 3100);
DISPLAY INVISIBLE (-5773 3100);
FORCEADD TAP..1
R 2
(-5775 3150);
FORCEPROP 3 LASTPIN (-5725 3150) SIG_NAME M_K_CPU0_SB_CA<5>
J 0
(-5715 3160);
DISPLAY 0.659574 (-5715 3160);
PAINT MONO (-5715 3160);
DISPLAY INVISIBLE (-5715 3160);
FORCEPROP 1 LASTPIN (-5725 3150) BN 5
J 2
(-5713 3158);
DISPLAY 0.489362 (-5713 3158);
PAINT GREEN (-5713 3158);
FORCEPROP 2 LAST CDS_LIB mstr_standard
J 0
(-5775 3150);
DISPLAY 0.723404 (-5775 3150);
PAINT MONO (-5775 3150);
DISPLAY INVISIBLE (-5775 3150);
FORCEPROP 1 LAST BODY_TYPE PLUMBING
J 2
(-5775 3200);
DISPLAY 0.872340 (-5775 3200);
PAINT GREEN (-5775 3200);
DISPLAY INVISIBLE (-5775 3200);
FORCEPROP 1 LAST HDL_TAP TRUE
J 2
(-6100 3025);
DISPLAY 0.872340 (-6100 3025);
DISPLAY INVISIBLE (-6100 3025);
FORCEPROP 1 LAST PATH I301
J 2
(-5773 3150);
DISPLAY 0.872340 (-5773 3150);
PAINT GREEN (-5773 3150);
DISPLAY INVISIBLE (-5773 3150);
FORCEADD OFFPAGE..2
R 2
(-6375 3825);
FORCEPROP 2 LAST $XR0 96 
J 0
(-6629 3825);
DISPLAY 0.638298 (-6629 3825);
PAINT MONO (-6629 3825);
FORCEPROP 2 LAST CDS_LIB standard
J 0
(-6375 3825);
DISPLAY INVISIBLE (-6375 3825);
FORCEPROP 1 LAST OFFPAGE TRUE
J 2
(-6700 3700);
DISPLAY 0.872340 (-6700 3700);
PAINT GREEN (-6700 3700);
DISPLAY INVISIBLE (-6700 3700);
FORCEPROP 1 LAST COMMENT_BODY TRUE
J 2
(-6330 3730);
DISPLAY 0.872340 (-6330 3730);
PAINT GREEN (-6330 3730);
DISPLAY INVISIBLE (-6330 3730);
FORCEPROP 2 LAST PATH I302
J 0
(-6650 3875);
DISPLAY 1.021277 (-6650 3875);
DISPLAY INVISIBLE (-6650 3875);
FORCEADD OFFPAGE..2
R 2
(-6375 3425);
FORCEPROP 2 LAST $XR0 96 
J 0
(-6629 3425);
DISPLAY 0.638298 (-6629 3425);
PAINT MONO (-6629 3425);
FORCEPROP 2 LAST CDS_LIB standard
J 0
(-6375 3425);
DISPLAY INVISIBLE (-6375 3425);
FORCEPROP 1 LAST OFFPAGE TRUE
J 2
(-6700 3300);
DISPLAY 0.872340 (-6700 3300);
PAINT GREEN (-6700 3300);
DISPLAY INVISIBLE (-6700 3300);
FORCEPROP 1 LAST COMMENT_BODY TRUE
J 2
(-6330 3330);
DISPLAY 0.872340 (-6330 3330);
PAINT GREEN (-6330 3330);
DISPLAY INVISIBLE (-6330 3330);
FORCEPROP 2 LAST PATH I303
J 0
(-6650 3475);
DISPLAY 1.021277 (-6650 3475);
DISPLAY INVISIBLE (-6650 3475);
FORCEADD OFFPAGE..2
R 2
(-6375 2950);
FORCEPROP 2 LAST $XR0 96 
J 0
(-6629 2950);
DISPLAY 0.638298 (-6629 2950);
PAINT MONO (-6629 2950);
FORCEPROP 2 LAST CDS_LIB standard
J 0
(-6375 2950);
DISPLAY INVISIBLE (-6375 2950);
FORCEPROP 1 LAST OFFPAGE TRUE
J 2
(-6700 2825);
DISPLAY 0.872340 (-6700 2825);
PAINT GREEN (-6700 2825);
DISPLAY INVISIBLE (-6700 2825);
FORCEPROP 1 LAST COMMENT_BODY TRUE
J 2
(-6330 2855);
DISPLAY 0.872340 (-6330 2855);
PAINT GREEN (-6330 2855);
DISPLAY INVISIBLE (-6330 2855);
FORCEPROP 2 LAST PATH I304
J 0
(-6650 3000);
DISPLAY 1.021277 (-6650 3000);
DISPLAY INVISIBLE (-6650 3000);
FORCEADD OFFPAGE..2
R 2
(-6375 2900);
FORCEPROP 2 LAST $XR0 96 
J 0
(-6629 2900);
DISPLAY 0.638298 (-6629 2900);
PAINT MONO (-6629 2900);
FORCEPROP 2 LAST CDS_LIB standard
J 0
(-6375 2900);
DISPLAY INVISIBLE (-6375 2900);
FORCEPROP 1 LAST OFFPAGE TRUE
J 2
(-6700 2775);
DISPLAY 0.872340 (-6700 2775);
PAINT GREEN (-6700 2775);
DISPLAY INVISIBLE (-6700 2775);
FORCEPROP 1 LAST COMMENT_BODY TRUE
J 2
(-6330 2805);
DISPLAY 0.872340 (-6330 2805);
PAINT GREEN (-6330 2805);
DISPLAY INVISIBLE (-6330 2805);
FORCEPROP 2 LAST PATH I305
J 0
(-6650 2950);
DISPLAY 1.021277 (-6650 2950);
DISPLAY INVISIBLE (-6650 2950);
FORCEADD OFFPAGE..2
R 2
(-6375 2800);
FORCEPROP 2 LAST $XR0 96 
J 0
(-6629 2800);
DISPLAY 0.638298 (-6629 2800);
PAINT MONO (-6629 2800);
FORCEPROP 2 LAST CDS_LIB standard
J 0
(-6375 2800);
DISPLAY INVISIBLE (-6375 2800);
FORCEPROP 1 LAST OFFPAGE TRUE
J 2
(-6700 2675);
DISPLAY 0.872340 (-6700 2675);
PAINT GREEN (-6700 2675);
DISPLAY INVISIBLE (-6700 2675);
FORCEPROP 1 LAST COMMENT_BODY TRUE
J 2
(-6330 2705);
DISPLAY 0.872340 (-6330 2705);
PAINT GREEN (-6330 2705);
DISPLAY INVISIBLE (-6330 2705);
FORCEPROP 2 LAST PATH I306
J 0
(-6650 2850);
DISPLAY 1.021277 (-6650 2850);
DISPLAY INVISIBLE (-6650 2850);
FORCEADD OFFPAGE..1
(-6375 2650);
FORCEPROP 2 LAST $XR0 96 
J 0
(-6596 2650);
DISPLAY 0.638298 (-6596 2650);
PAINT MONO (-6596 2650);
FORCEPROP 2 LAST CDS_LIB standard
J 0
(-6375 2650);
DISPLAY INVISIBLE (-6375 2650);
FORCEPROP 1 LAST OFFPAGE TRUE
J 0
(-6050 2525);
DISPLAY 0.872340 (-6050 2525);
PAINT GREEN (-6050 2525);
DISPLAY INVISIBLE (-6050 2525);
FORCEPROP 1 LAST COMMENT_BODY TRUE
J 0
(-6250 2550);
DISPLAY 0.872340 (-6250 2550);
PAINT GREEN (-6250 2550);
DISPLAY INVISIBLE (-6250 2550);
FORCEPROP 2 LAST PATH I307
J 0
(-6625 2700);
DISPLAY 1.021277 (-6625 2700);
DISPLAY INVISIBLE (-6625 2700);
FORCEADD OFFPAGE..2
R 2
(-6375 2750);
FORCEPROP 2 LAST $XR0 96 
J 0
(-6629 2750);
DISPLAY 0.638298 (-6629 2750);
PAINT MONO (-6629 2750);
FORCEPROP 2 LAST CDS_LIB standard
J 0
(-6375 2750);
DISPLAY INVISIBLE (-6375 2750);
FORCEPROP 1 LAST OFFPAGE TRUE
J 2
(-6700 2625);
DISPLAY 0.872340 (-6700 2625);
PAINT GREEN (-6700 2625);
DISPLAY INVISIBLE (-6700 2625);
FORCEPROP 1 LAST COMMENT_BODY TRUE
J 2
(-6330 2655);
DISPLAY 0.872340 (-6330 2655);
PAINT GREEN (-6330 2655);
DISPLAY INVISIBLE (-6330 2655);
FORCEPROP 2 LAST PATH I308
J 0
(-6650 2800);
DISPLAY 1.021277 (-6650 2800);
DISPLAY INVISIBLE (-6650 2800);
FORCEADD OFFPAGE..5
(-6375 2550);
FORCEPROP 2 LAST $XR0 96 
J 0
(-6629 2550);
DISPLAY 0.638298 (-6629 2550);
PAINT MONO (-6629 2550);
FORCEPROP 2 LAST CDS_LIB mstr_standard
J 0
(-6375 2550);
DISPLAY INVISIBLE (-6375 2550);
FORCEPROP 1 LAST OFFPAGE TRUE
J 0
(-6050 2425);
DISPLAY 0.872340 (-6050 2425);
PAINT GREEN (-6050 2425);
DISPLAY INVISIBLE (-6050 2425);
FORCEPROP 1 LAST COMMENT_BODY TRUE
J 0
(-6275 2475);
DISPLAY 0.872340 (-6275 2475);
PAINT GREEN (-6275 2475);
DISPLAY INVISIBLE (-6275 2475);
FORCEPROP 2 LAST PATH I309
J 0
(-6650 2600);
DISPLAY 1.021277 (-6650 2600);
DISPLAY INVISIBLE (-6650 2600);
FORCEADD OFFPAGE..2
R 2
(-6375 2450);
FORCEPROP 2 LAST $XR0 96 
J 0
(-6629 2450);
DISPLAY 0.638298 (-6629 2450);
PAINT MONO (-6629 2450);
FORCEPROP 2 LAST CDS_LIB standard
J 0
(-6375 2450);
DISPLAY INVISIBLE (-6375 2450);
FORCEPROP 1 LAST OFFPAGE TRUE
J 2
(-6700 2325);
DISPLAY 0.872340 (-6700 2325);
PAINT GREEN (-6700 2325);
DISPLAY INVISIBLE (-6700 2325);
FORCEPROP 1 LAST COMMENT_BODY TRUE
J 2
(-6330 2355);
DISPLAY 0.872340 (-6330 2355);
PAINT GREEN (-6330 2355);
DISPLAY INVISIBLE (-6330 2355);
FORCEPROP 2 LAST PATH I310
J 0
(-6650 2500);
DISPLAY 1.021277 (-6650 2500);
DISPLAY INVISIBLE (-6650 2500);
FORCEADD OFFPAGE..2
R 2
(-6375 2400);
FORCEPROP 2 LAST $XR0 96 
J 0
(-6629 2400);
DISPLAY 0.638298 (-6629 2400);
PAINT MONO (-6629 2400);
FORCEPROP 2 LAST CDS_LIB standard
J 0
(-6375 2400);
DISPLAY INVISIBLE (-6375 2400);
FORCEPROP 1 LAST OFFPAGE TRUE
J 2
(-6700 2275);
DISPLAY 0.872340 (-6700 2275);
PAINT GREEN (-6700 2275);
DISPLAY INVISIBLE (-6700 2275);
FORCEPROP 1 LAST COMMENT_BODY TRUE
J 2
(-6330 2305);
DISPLAY 0.872340 (-6330 2305);
PAINT GREEN (-6330 2305);
DISPLAY INVISIBLE (-6330 2305);
FORCEPROP 2 LAST PATH I311
J 0
(-6650 2450);
DISPLAY 1.021277 (-6650 2450);
DISPLAY INVISIBLE (-6650 2450);
FORCEADD OFFPAGE..1
(-6375 2300);
FORCEPROP 2 LAST $XR0 96 
J 0
(-6596 2300);
DISPLAY 0.638298 (-6596 2300);
PAINT MONO (-6596 2300);
FORCEPROP 2 LAST CDS_LIB standard
J 0
(-6375 2300);
DISPLAY INVISIBLE (-6375 2300);
FORCEPROP 1 LAST OFFPAGE TRUE
J 0
(-6050 2175);
DISPLAY 0.872340 (-6050 2175);
PAINT GREEN (-6050 2175);
DISPLAY INVISIBLE (-6050 2175);
FORCEPROP 1 LAST COMMENT_BODY TRUE
J 0
(-6250 2200);
DISPLAY 0.872340 (-6250 2200);
PAINT GREEN (-6250 2200);
DISPLAY INVISIBLE (-6250 2200);
FORCEPROP 2 LAST PATH I312
J 0
(-6625 2350);
DISPLAY 1.021277 (-6625 2350);
DISPLAY INVISIBLE (-6625 2350);
FORCEADD OFFPAGE..5
(-6375 2200);
FORCEPROP 2 LAST $XR0 96 
J 0
(-6629 2200);
DISPLAY 0.638298 (-6629 2200);
PAINT MONO (-6629 2200);
FORCEPROP 2 LAST CDS_LIB standard
J 0
(-6375 2200);
DISPLAY INVISIBLE (-6375 2200);
FORCEPROP 1 LAST OFFPAGE TRUE
J 0
(-6050 2075);
DISPLAY 0.872340 (-6050 2075);
PAINT GREEN (-6050 2075);
DISPLAY INVISIBLE (-6050 2075);
FORCEPROP 1 LAST COMMENT_BODY TRUE
J 0
(-6275 2125);
DISPLAY 0.872340 (-6275 2125);
PAINT GREEN (-6275 2125);
DISPLAY INVISIBLE (-6275 2125);
FORCEPROP 2 LAST PATH I313
J 0
(-6650 2250);
DISPLAY 1.021277 (-6650 2250);
DISPLAY INVISIBLE (-6650 2250);
FORCEADD Q_RES..1
(-6700 2100);
FORCEPROP 1 LAST LOCATION R385
J 0
(-7025 2100);
DISPLAY 0.489362 (-7025 2100);
PAINT SKYBLUE (-7025 2100);
FORCEPROP 0 LAST $SEC 1
J 0
(-6875 2150);
DISPLAY 0.680851 (-6875 2150);
PAINT MONO (-6875 2150);
DISPLAY INVISIBLE (-6875 2150);
FORCEPROP 0 LAST CDS_SEC 1
J 0
(-6875 2150);
DISPLAY 1.021277 (-6875 2150);
DISPLAY INVISIBLE (-6875 2150);
FORCEPROP 1 LASTPIN (-6800 2100) $PN 1
J 0
(-6788 2112);
DISPLAY 0.489362 (-6788 2112);
PAINT MONO (-6788 2112);
FORCEPROP 1 LASTPIN (-6600 2100) $PN 2
J 0
(-6638 2112);
DISPLAY 0.489362 (-6638 2112);
PAINT MONO (-6638 2112);
FORCEPROP 1 LAST PACK_TYPE 0402LF
J 0
(-7025 2075);
DISPLAY 0.489362 (-7025 2075);
PAINT SKYBLUE (-7025 2075);
FORCEPROP 1 LAST TOLERANCE 1%
J 0
(-6425 2100);
DISPLAY 0.489362 (-6425 2100);
PAINT SKYBLUE (-6425 2100);
FORCEPROP 1 LAST VALUE 15
J 2
(-6375 2100);
DISPLAY 0.489362 (-6375 2100);
PAINT SKYBLUE (-6375 2100);
FORCEPROP 1 LAST MATERIAL CHIP
J 0
(-6825 2225);
DISPLAY 0.638298 (-6825 2225);
PAINT SKYBLUE (-6825 2225);
DISPLAY INVISIBLE (-6825 2225);
FORCEPROP 1 LAST WATTAGE 1/16W
J 2
(-6475 2225);
DISPLAY 0.638298 (-6475 2225);
PAINT SKYBLUE (-6475 2225);
DISPLAY INVISIBLE (-6475 2225);
FORCEPROP 2 LAST CDS_LIB pure_quanta
J 0
(-6700 2100);
DISPLAY INVISIBLE (-6700 2100);
FORCEPROP 1 LAST PATH I314
J 0
(-6750 2250);
DISPLAY 0.978723 (-6750 2250);
PAINT WHITE (-6750 2250);
DISPLAY INVISIBLE (-6750 2250);
FORCEPROP 1 LAST PART_NUMBER CS01502FB03
J 0
(-6575 2075);
DISPLAY 0.489362 (-6575 2075);
PAINT SKYBLUE (-6575 2075);
DISPLAY INVISIBLE (-6575 2075);
FORCEADD OFFPAGE..1
(-7575 2100);
FORCEPROP 2 LAST $XR0 96 
J 0
(-7826 2100);
DISPLAY 0.638298 (-7826 2100);
PAINT MONO (-7826 2100);
FORCEPROP 2 LAST CDS_LIB mstr_standard
J 0
(-7575 2100);
DISPLAY INVISIBLE (-7575 2100);
FORCEPROP 1 LAST OFFPAGE TRUE
J 0
(-7250 1975);
DISPLAY 0.872340 (-7250 1975);
PAINT GREEN (-7250 1975);
DISPLAY INVISIBLE (-7250 1975);
FORCEPROP 1 LAST COMMENT_BODY TRUE
J 0
(-7450 2000);
DISPLAY 0.872340 (-7450 2000);
PAINT GREEN (-7450 2000);
DISPLAY INVISIBLE (-7450 2000);
FORCEPROP 2 LAST PATH I315
J 0
(-7850 2150);
DISPLAY 1.021277 (-7850 2150);
DISPLAY INVISIBLE (-7850 2150);
FORCEADD OFFPAGE..5
(-6375 2000);
FORCEPROP 2 LAST $XR0 96 
J 0
(-6629 2000);
DISPLAY 0.638298 (-6629 2000);
PAINT MONO (-6629 2000);
FORCEPROP 2 LAST CDS_LIB standard
J 0
(-6375 2000);
DISPLAY INVISIBLE (-6375 2000);
FORCEPROP 1 LAST OFFPAGE TRUE
J 0
(-6050 1875);
DISPLAY 0.872340 (-6050 1875);
PAINT GREEN (-6050 1875);
DISPLAY INVISIBLE (-6050 1875);
FORCEPROP 1 LAST COMMENT_BODY TRUE
J 0
(-6275 1925);
DISPLAY 0.872340 (-6275 1925);
PAINT GREEN (-6275 1925);
DISPLAY INVISIBLE (-6275 1925);
FORCEPROP 2 LAST PATH I316
J 0
(-6650 2050);
DISPLAY 1.021277 (-6650 2050);
DISPLAY INVISIBLE (-6650 2050);
FORCEADD CAD_NOTE..1
(-7525 2400);
FORCEPROP 0 LAST L1 R1950 PLACE CLOSE TO CPU < 25MM
J 0
(-7675 2275);
DISPLAY 0.617021 (-7675 2275);
PAINT WHITE (-7675 2275);
FORCEPROP 2 LAST CDS_LIB pure_quanta_power
J 0
(-7525 2400);
DISPLAY INVISIBLE (-7525 2400);
FORCEPROP 1 LAST COMMENT_BODY TRUE
J 0
(-7500 2500);
DISPLAY 0.574468 (-7500 2500);
PAINT WHITE (-7500 2500);
DISPLAY INVISIBLE (-7500 2500);
FORCEADD QUANTA_TITLE_BLOCK_C..1
(0 0);
FORCEPROP 0 LAST CDS_CON_LAST_MODIFIED Thu Sep 14 16:11:51 2023
J 0
(-1885 15);
DISPLAY INVISIBLE (-1885 15);
FORCEPROP 1 LAST CUSTOM_TXT_CDS <CON_LAST_MODIFIED>
J 0
(-1885 15);
DISPLAY 0.978723 (-1885 15);
FORCEPROP 2 LAST CUSTOM_TXT_CDS <XR_PAGE_TITLE>
J 0
(-7890 5250);
DISPLAY 0.638298 (-7890 5250);
PAINT PINK (-7890 5250);
DISPLAY INVISIBLE (-7890 5250);
FORCEPROP 1 LAST CUSTOM_TXT_CDS <NAME_2>
J 0
(-3175 50);
FORCEPROP 1 LAST CUSTOM_TXT_CDS <NAME_1>
J 0
(-3175 175);
FORCEPROP 1 LAST CUSTOM_TXT_CDS <Q_NUMBER>
J 0
(-1403 103);
DISPLAY 1.212766 (-1403 103);
FORCEPROP 1 LAST CUSTOM_TXT_CDS <Q_PROJ>
J 0
(-2382 102);
DISPLAY 1.212766 (-2382 102);
FORCEPROP 1 LAST CUSTOM_TXT_CDS <Q_REV>
J 0
(-184 103);
DISPLAY 1.212766 (-184 103);
FORCEPROP 1 LAST CUSTOM_TXT_CDS <CON_PAGE_NUM> OF <CON_TOTAL_PAGES>
J 0
(-446 18);
DISPLAY 0.978723 (-446 18);
FORCEPROP 1 LAST Q_TITLE CPU0 DDR CHK
J 0
(-9325 50);
DISPLAY 2.446809 (-9325 50);
PAINT GREEN (-9325 50);
FORCEPROP 1 LAST CDS_LMAN_SYM_OUTLINE -9475,6775,100,-125
J 0
(0 0);
DISPLAY 0.468085 (0 0);
PAINT GREEN (0 0);
DISPLAY INVISIBLE (0 0);
FORCEPROP 2 LAST CDS_LIB pure_quanta
J 0
(0 0);
DISPLAY INVISIBLE (0 0);
FORCEPROP 2 LAST PAGE_BORDER TRUE
J 0
(-7890 5250);
DISPLAY 0.638298 (-7890 5250);
PAINT PINK (-7890 5250);
DISPLAY INVISIBLE (-7890 5250);
FORCEPROP 2 LAST CDS_XR_PAGE_TITLE CR-20 : @T6G_MB_LIB.T6G(SCH_1):PAGE20
J 0
(-7890 5250);
DISPLAY 0.638298 (-7890 5250);
PAINT PINK (-7890 5250);
DISPLAY INVISIBLE (-7890 5250);
FORCEPROP 1 LAST Q_DEPT BU9
J 1
(-3763 49);
DISPLAY 1.957447 (-3763 49);
PAINT GREEN (-3763 49);
DISPLAY INVISIBLE (-3763 49);
FORCEPROP 1 LAST COMMENT_BODY TRUE
J 0
(12 -13);
DISPLAY 0.978723 (12 -13);
PAINT GREEN (12 -13);
DISPLAY INVISIBLE (12 -13);
WIRE 17 -1 (-3100 5475)(-3100 5425);
WIRE 17 -1 (-3100 5525)(-3100 5475);
WIRE 17 -1 (-3100 5425)(-3100 5375);
WIRE 17 -1 (-3100 5375)(-3100 5325);
WIRE 17 -1 (-3100 5625)(-3100 5525);
WIRE 17 -1 (-3100 5675)(-3100 5625);
WIRE 17 -1 (-3100 5325)(-3100 5275);
WIRE 17 -1 (-3100 5275)(-3100 5225);
WIRE 17 -1 (-3100 5725)(-3100 5675);
WIRE 17 -1 (-3100 5775)(-3100 5725);
WIRE 17 -1 (-3100 5225)(-3100 5175);
WIRE 17 -1 (-3100 5075)(-3100 5175);
WIRE 17 -1 (-3100 5825)(-3100 5775);
WIRE 17 -1 (-3100 5875)(-3100 5825);
WIRE 17 -1 (-3100 5025)(-3100 5075);
WIRE 17 -1 (-3100 4975)(-3100 5025);
WIRE 17 -1 (-3100 5925)(-3100 5875);
WIRE 17 -1 (-3100 5975)(-3100 5925);
WIRE 17 -1 (-3100 4925)(-3100 4975);
WIRE 17 -1 (-3100 4925)(-3100 4875);
WIRE 17 -1 (-3100 5975)(-2475 5975);
FORCEPROP 2 LAST SIG_NAME M_K_CPU0_SA_DQ<31:0>
J 2
(-2535 5985);
DISPLAY 0.489362 (-2535 5985);
WIRE 17 -1 (-3100 4875)(-3100 4825);
WIRE 17 -1 (-3100 4825)(-3100 4775);
WIRE 17 -1 (-3100 4775)(-3100 4725);
WIRE 17 -1 (-3100 4725)(-3100 4625);
WIRE 17 -1 (-3100 4625)(-3100 4575);
WIRE 17 -1 (-3100 4575)(-3100 4525);
WIRE 17 -1 (-3100 4525)(-3100 4475);
WIRE 17 -1 (-3100 4425)(-3100 4475);
WIRE 17 -1 (-3100 4375)(-3100 4425);
WIRE 17 -1 (-3100 4325)(-3100 4375);
WIRE 17 -1 (-3100 4275)(-3100 4325);
WIRE 17 -1 (-2475 4175)(-3100 4175);
FORCEPROP 2 LAST SIG_NAME M_K_CPU0_SB_DQ<31:0>
J 2
(-2535 4185);
DISPLAY 0.489362 (-2535 4185);
WIRE 17 -1 (-3100 4175)(-3100 4125);
WIRE 17 -1 (-3100 3125)(-3100 3175);
WIRE 17 -1 (-3100 3125)(-3100 3075);
WIRE 17 -1 (-3100 3175)(-3100 3225);
WIRE 17 -1 (-3100 3225)(-3100 3275);
WIRE 17 -1 (-3100 3075)(-3100 3025);
WIRE 17 -1 (-3100 3025)(-3100 2975);
WIRE 17 -1 (-3100 3275)(-3100 3375);
WIRE 17 -1 (-3100 3425)(-3100 3375);
WIRE 17 -1 (-3100 2975)(-3100 2925);
WIRE 17 -1 (-3100 2925)(-3100 2825);
WIRE 17 -1 (-3100 3475)(-3100 3425);
WIRE 17 -1 (-3100 3525)(-3100 3475);
WIRE 17 -1 (-3100 2825)(-3100 2775);
WIRE 17 -1 (-3100 2775)(-3100 2725);
WIRE 17 -1 (-3100 3575)(-3100 3525);
WIRE 17 -1 (-3100 3625)(-3100 3575);
WIRE 17 -1 (-3100 2725)(-3100 2675);
WIRE 17 -1 (-3100 2625)(-3100 2675);
WIRE 17 -1 (-3100 3675)(-3100 3625);
WIRE 17 -1 (-3100 3725)(-3100 3675);
WIRE 17 -1 (-3100 2575)(-3100 2625);
WIRE 17 -1 (-3100 2525)(-3100 2575);
WIRE 17 -1 (-3100 3825)(-3100 3725);
WIRE 17 -1 (-3100 3875)(-3100 3825);
WIRE 17 -1 (-3100 2475)(-3100 2525);
WIRE 17 -1 (-3100 3925)(-3100 3875);
WIRE 17 -1 (-3100 3975)(-3100 3925);
WIRE 17 -1 (-3100 4025)(-3100 3975);
WIRE 17 -1 (-3100 4075)(-3100 4025);
WIRE 17 -1 (-3100 4125)(-3100 4075);
WIRE 17 -1 (-3100 2375)(-3100 2400);
WIRE 17 -1 (-3100 2375)(-3100 2325);
WIRE 17 -1 (-3100 2400)(-2600 2400);
FORCEPROP 2 LAST SIG_NAME M_K_CPU0_SA_CB<7:0>
J 2
(-2600 2410);
DISPLAY 0.489362 (-2600 2410);
WIRE 17 -1 (-3100 2275)(-3100 2325);
WIRE 17 -1 (-3100 2275)(-3100 2225);
WIRE 17 -1 (-3100 2175)(-3100 2225);
WIRE 17 -1 (-3100 2125)(-3100 2175);
WIRE 17 -1 (-3100 2075)(-3100 2125);
WIRE 17 -1 (-3100 2025)(-3100 2075);
WIRE 17 -1 (-3100 1925)(-3100 1950);
WIRE 17 -1 (-3100 1925)(-3100 1875);
WIRE 17 -1 (-3100 1950)(-2600 1950);
FORCEPROP 2 LAST SIG_NAME M_K_CPU0_SB_CB<7:0>
J 2
(-2600 1960);
DISPLAY 0.489362 (-2600 1960);
WIRE 17 -1 (-3100 1825)(-3100 1875);
WIRE 17 -1 (-3100 1825)(-3100 1775);
WIRE 17 -1 (-3100 1725)(-3100 1775);
WIRE 17 -1 (-3100 1675)(-3100 1725);
WIRE 17 -1 (-3100 1625)(-3100 1675);
WIRE 17 -1 (-3100 1575)(-3100 1625);
WIRE 17 -1 (-5625 5975)(-5625 5875);
WIRE 17 -1 (-5625 5975)(-6425 5975);
FORCEPROP 2 LAST SIG_NAME M_K_CPU0_SA_DQS_DP<9:0>
J 2
(-5860 5985);
DISPLAY 0.489362 (-5860 5985);
WIRE 17 -1 (-5625 5875)(-5625 5775);
WIRE 17 -1 (-5625 5775)(-5625 5675);
WIRE 17 -1 (-5625 5675)(-5625 5575);
WIRE 17 -1 (-5625 5475)(-5625 5575);
WIRE 17 -1 (-5625 5275)(-5625 5175);
WIRE 17 -1 (-5625 5275)(-5625 5375);
WIRE 17 -1 (-5625 5175)(-5625 5075);
WIRE 17 -1 (-5625 5375)(-5625 5475);
WIRE 17 -1 (-5825 5925)(-5825 5825);
FORCEPROP 2 LAST SIG_NAME M_K_CPU0_SA_DQS_DN<9:0>
J 2
(-5860 5935);
DISPLAY 0.489362 (-5860 5935);
WIRE 17 -1 (-5825 5825)(-5825 5725);
WIRE 17 -1 (-5825 5725)(-5825 5625);
WIRE 17 -1 (-5825 5625)(-5825 5525);
WIRE 17 -1 (-5825 5425)(-5825 5525);
WIRE 17 -1 (-5825 5325)(-5825 5425);
WIRE 17 -1 (-5825 5225)(-5825 5325);
WIRE 17 -1 (-5825 5225)(-5825 5125);
WIRE 17 -1 (-5825 5125)(-5825 5025);
WIRE 17 -1 (-5625 4825)(-5625 4725);
WIRE 17 -1 (-5625 4925)(-5625 4825);
WIRE 17 -1 (-5625 4725)(-5625 4625);
WIRE 17 -1 (-5625 4625)(-5625 4525);
WIRE 17 -1 (-5625 4925)(-6425 4925);
FORCEPROP 2 LAST SIG_NAME M_K_CPU0_SB_DQS_DP<9:0>
J 2
(-5860 4935);
DISPLAY 0.489362 (-5860 4935);
WIRE 17 -1 (-5625 4425)(-5625 4525);
WIRE 17 -1 (-5625 4325)(-5625 4425);
WIRE 17 -1 (-5625 4225)(-5625 4325);
WIRE 17 -1 (-5625 4225)(-5625 4125);
WIRE 17 -1 (-5625 4125)(-5625 4025);
WIRE 17 -1 (-5825 4275)(-5825 4375);
WIRE 17 -1 (-5825 4175)(-5825 4275);
WIRE 17 -1 (-5825 4375)(-5825 4475);
WIRE 17 -1 (-5825 4575)(-5825 4475);
WIRE 17 -1 (-5825 4175)(-5825 4075);
WIRE 17 -1 (-5825 4075)(-5825 3975);
WIRE 17 -1 (-5825 4675)(-5825 4575);
WIRE 17 -1 (-5825 4775)(-5825 4675);
WIRE 17 -1 (-5825 4875)(-5825 4775);
FORCEPROP 2 LAST SIG_NAME M_K_CPU0_SB_DQS_DN<9:0>
J 2
(-5860 4885);
DISPLAY 0.489362 (-5860 4885);
WIRE 17 -1 (-5825 3375)(-5825 3425);
WIRE 17 -1 (-5825 3325)(-5825 3375);
WIRE 17 -1 (-5825 3425)(-6325 3425);
FORCEPROP 2 LAST SIG_NAME M_K_CPU0_SB_CA<6:0>
J 0
(-6325 3435);
DISPLAY 0.489362 (-6325 3435);
WIRE 17 -1 (-5825 3775)(-5825 3825);
WIRE 17 -1 (-5825 3725)(-5825 3775);
WIRE 17 -1 (-5825 3825)(-6325 3825);
FORCEPROP 2 LAST SIG_NAME M_K_CPU0_SA_CA<6:0>
J 0
(-6325 3835);
DISPLAY 0.489362 (-6325 3835);
WIRE 17 -1 (-5825 3675)(-5825 3725);
WIRE 17 -1 (-5825 3275)(-5825 3325);
WIRE 17 -1 (-5825 3625)(-5825 3675);
WIRE 17 -1 (-5825 3575)(-5825 3625);
WIRE 17 -1 (-5825 3525)(-5825 3575);
WIRE 17 -1 (-5825 3225)(-5825 3275);
WIRE 17 -1 (-5825 3175)(-5825 3225);
WIRE 17 -1 (-5825 3125)(-5825 3175);
WIRE 17 -1 (-5825 5925)(-6425 5925);
WIRE 17 -1 (-5825 4875)(-6425 4875);
WIRE 16 -1 (-7525 2100)(-6800 2100);
FORCEPROP 2 LAST SIG_NAME M_K_CPU0_ALERT_N
J 0
(-7485 2110);
DISPLAY 0.489362 (-7485 2110);
WIRE 16 -1 (-6600 2100)(-5225 2100);
FORCEPROP 2 LAST SIG_NAME M_K_CPU0_ALERT_R_N
J 0
(-6310 2110);
DISPLAY 0.489362 (-6310 2110);
FORCEPROP 2 LASTPROP $XRERR UNIQUE?
J 0
(-6550 2110);
DISPLAY 0.638298 (-6550 2110);
PAINT MONO (-6550 2110);
DISPLAY INVISIBLE (-6550 2110);
WIRE 16 -1 (-6325 1150)(-5225 1150);
FORCEPROP 2 LAST SIG_NAME TP_M_K_CPU0_SA_TEST39K
J 0
(-6310 1160);
DISPLAY 0.489362 (-6310 1160);
FORCEPROP 2 LASTPROP $XRERR UNIQUE?
J 0
(-6565 1150);
DISPLAY 0.638298 (-6565 1150);
PAINT MONO (-6565 1150);
DISPLAY INVISIBLE (-6565 1150);
WIRE 16 -1 (-6325 2950)(-5225 2950);
FORCEPROP 2 LAST SIG_NAME M_K_CPU0_CLK_DP<0>
J 0
(-6325 2960);
DISPLAY 0.489362 (-6325 2960);
WIRE 16 -1 (-6325 2900)(-5225 2900);
FORCEPROP 2 LAST SIG_NAME M_K_CPU0_CLK_DN<0>
J 0
(-6325 2910);
DISPLAY 0.489362 (-6325 2910);
WIRE 16 -1 (-6325 2800)(-5225 2800);
FORCEPROP 2 LAST SIG_NAME M_K_CPU0_SA_CS_N<0>
J 0
(-6325 2810);
DISPLAY 0.489362 (-6325 2810);
WIRE 16 -1 (-6325 2650)(-5225 2650);
FORCEPROP 2 LAST SIG_NAME M_K_CPU0_SA_RSP<0>
J 0
(-6325 2660);
DISPLAY 0.489362 (-6325 2660);
WIRE 16 -1 (-6325 2750)(-5225 2750);
FORCEPROP 2 LAST SIG_NAME M_K_CPU0_SA_CS_N<1>
J 0
(-6325 2760);
DISPLAY 0.489362 (-6325 2760);
WIRE 16 -1 (-6325 2550)(-5225 2550);
FORCEPROP 2 LAST SIG_NAME M_K_CPU0_SA_PAR
J 0
(-6325 2560);
DISPLAY 0.489362 (-6325 2560);
WIRE 16 -1 (-6325 2450)(-5225 2450);
FORCEPROP 2 LAST SIG_NAME M_K_CPU0_SB_CS_N<0>
J 0
(-6325 2460);
DISPLAY 0.489362 (-6325 2460);
WIRE 16 -1 (-6325 2400)(-5225 2400);
FORCEPROP 2 LAST SIG_NAME M_K_CPU0_SB_CS_N<1>
J 0
(-6325 2410);
DISPLAY 0.489362 (-6325 2410);
WIRE 16 -1 (-6325 2300)(-5225 2300);
FORCEPROP 2 LAST SIG_NAME M_K_CPU0_SB_RSP<0>
J 0
(-6325 2310);
DISPLAY 0.489362 (-6325 2310);
WIRE 16 -1 (-6325 2200)(-5225 2200);
FORCEPROP 2 LAST SIG_NAME M_K_CPU0_SB_PAR
J 0
(-6325 2210);
DISPLAY 0.489362 (-6325 2210);
WIRE 16 -1 (-6325 2000)(-5225 2000);
FORCEPROP 2 LAST SIG_NAME M_K_CPU0_RESET_N
J 0
(-6325 2010);
DISPLAY 0.489362 (-6325 2010);
WIRE 16 -1 (-5725 3800)(-5225 3800);
WIRE 16 -1 (-5725 3100)(-5225 3100);
WIRE 16 -1 (-5725 3500)(-5225 3500);
WIRE 16 -1 (-5725 3150)(-5225 3150);
WIRE 16 -1 (-5725 3550)(-5225 3550);
WIRE 16 -1 (-5725 3200)(-5225 3200);
WIRE 16 -1 (-5725 3600)(-5225 3600);
WIRE 16 -1 (-5725 3250)(-5225 3250);
WIRE 16 -1 (-5725 3950)(-5225 3950);
WIRE 16 -1 (-5725 3650)(-5225 3650);
WIRE 16 -1 (-5725 3300)(-5225 3300);
WIRE 16 -1 (-5725 4050)(-5225 4050);
WIRE 16 -1 (-5725 3700)(-5225 3700);
WIRE 16 -1 (-5725 3350)(-5225 3350);
WIRE 16 -1 (-5725 3750)(-5225 3750);
WIRE 16 -1 (-5725 3400)(-5225 3400);
WIRE 16 -1 (-5525 4000)(-5225 4000);
WIRE 16 -1 (-5725 4350)(-5225 4350);
WIRE 16 -1 (-5725 4450)(-5225 4450);
WIRE 16 -1 (-5725 5000)(-5225 5000);
WIRE 16 -1 (-5725 4550)(-5225 4550);
WIRE 16 -1 (-5725 5100)(-5225 5100);
WIRE 16 -1 (-5725 4650)(-5225 4650);
WIRE 16 -1 (-5725 4750)(-5225 4750);
WIRE 16 -1 (-5725 4850)(-5225 4850);
WIRE 16 -1 (-5725 4150)(-5225 4150);
WIRE 16 -1 (-5725 4250)(-5225 4250);
WIRE 16 -1 (-5525 4100)(-5225 4100);
WIRE 16 -1 (-5525 4200)(-5225 4200);
WIRE 16 -1 (-5525 4300)(-5225 4300);
WIRE 16 -1 (-5525 4400)(-5225 4400);
WIRE 16 -1 (-5525 4500)(-5225 4500);
WIRE 16 -1 (-5525 4600)(-5225 4600);
WIRE 16 -1 (-5525 4800)(-5225 4800);
WIRE 16 -1 (-5525 4900)(-5225 4900);
WIRE 16 -1 (-5525 5050)(-5225 5050);
WIRE 16 -1 (-5525 4700)(-5225 4700);
WIRE 16 -1 (-5725 5200)(-5225 5200);
WIRE 16 -1 (-5725 5300)(-5225 5300);
WIRE 16 -1 (-5725 5400)(-5225 5400);
WIRE 16 -1 (-5725 5500)(-5225 5500);
WIRE 16 -1 (-5725 5600)(-5225 5600);
WIRE 16 -1 (-5725 5700)(-5225 5700);
WIRE 16 -1 (-5725 5800)(-5225 5800);
WIRE 16 -1 (-5725 5900)(-5225 5900);
WIRE 16 -1 (-5525 5250)(-5225 5250);
WIRE 16 -1 (-5525 5350)(-5225 5350);
WIRE 16 -1 (-5525 5450)(-5225 5450);
WIRE 16 -1 (-5525 5550)(-5225 5550);
WIRE 16 -1 (-5525 5150)(-5225 5150);
WIRE 16 -1 (-5525 5650)(-5225 5650);
WIRE 16 -1 (-5525 5750)(-5225 5750);
WIRE 16 -1 (-5525 5850)(-5225 5850);
WIRE 16 -1 (-5525 5950)(-5225 5950);
WIRE 16 -1 (-3625 1550)(-3200 1550);
WIRE 16 -1 (-3625 1600)(-3200 1600);
WIRE 16 -1 (-3625 1650)(-3200 1650);
WIRE 16 -1 (-3625 1700)(-3200 1700);
WIRE 16 -1 (-3625 1750)(-3200 1750);
WIRE 16 -1 (-3625 1800)(-3200 1800);
WIRE 16 -1 (-3625 2000)(-3200 2000);
WIRE 16 -1 (-3625 1850)(-3200 1850);
WIRE 16 -1 (-3625 1900)(-3200 1900);
WIRE 16 -1 (-3625 2550)(-3200 2550);
WIRE 16 -1 (-3625 2600)(-3200 2600);
WIRE 16 -1 (-3625 2650)(-3200 2650);
WIRE 16 -1 (-3625 2700)(-3200 2700);
WIRE 16 -1 (-3625 2750)(-3200 2750);
WIRE 16 -1 (-3625 2800)(-3200 2800);
WIRE 16 -1 (-3625 2900)(-3200 2900);
WIRE 16 -1 (-3625 2950)(-3200 2950);
WIRE 16 -1 (-3625 3000)(-3200 3000);
WIRE 16 -1 (-3625 2050)(-3200 2050);
WIRE 16 -1 (-3625 3050)(-3200 3050);
WIRE 16 -1 (-3625 2450)(-3200 2450);
WIRE 16 -1 (-3625 2100)(-3200 2100);
WIRE 16 -1 (-3625 2500)(-3200 2500);
WIRE 16 -1 (-3625 2150)(-3200 2150);
WIRE 16 -1 (-3625 2200)(-3200 2200);
WIRE 16 -1 (-3625 2250)(-3200 2250);
WIRE 16 -1 (-3625 2300)(-3200 2300);
WIRE 16 -1 (-3625 2350)(-3200 2350);
WIRE 16 -1 (-3625 3650)(-3200 3650);
WIRE 16 -1 (-3625 3150)(-3200 3150);
WIRE 16 -1 (-3625 3700)(-3200 3700);
WIRE 16 -1 (-3625 3200)(-3200 3200);
WIRE 16 -1 (-3625 3800)(-3200 3800);
WIRE 16 -1 (-3625 3250)(-3200 3250);
WIRE 16 -1 (-3625 3850)(-3200 3850);
WIRE 16 -1 (-3625 3350)(-3200 3350);
WIRE 16 -1 (-3625 3900)(-3200 3900);
WIRE 16 -1 (-3625 3400)(-3200 3400);
WIRE 16 -1 (-3625 3950)(-3200 3950);
WIRE 16 -1 (-3625 3450)(-3200 3450);
WIRE 16 -1 (-3625 4000)(-3200 4000);
WIRE 16 -1 (-3625 3500)(-3200 3500);
WIRE 16 -1 (-3625 4050)(-3200 4050);
WIRE 16 -1 (-3625 3550)(-3200 3550);
WIRE 16 -1 (-3625 3600)(-3200 3600);
WIRE 16 -1 (-3625 3100)(-3200 3100);
WIRE 16 -1 (-3625 4900)(-3200 4900);
WIRE 16 -1 (-3625 4950)(-3200 4950);
WIRE 16 -1 (-3625 4350)(-3200 4350);
WIRE 16 -1 (-3625 5000)(-3200 5000);
WIRE 16 -1 (-3625 4400)(-3200 4400);
WIRE 16 -1 (-3625 5050)(-3200 5050);
WIRE 16 -1 (-3625 4450)(-3200 4450);
WIRE 16 -1 (-3625 4100)(-3200 4100);
WIRE 16 -1 (-3625 4500)(-3200 4500);
WIRE 16 -1 (-3625 4150)(-3200 4150);
WIRE 16 -1 (-3625 4550)(-3200 4550);
WIRE 16 -1 (-3625 4600)(-3200 4600);
WIRE 16 -1 (-3625 4700)(-3200 4700);
WIRE 16 -1 (-3625 4750)(-3200 4750);
WIRE 16 -1 (-3625 4800)(-3200 4800);
WIRE 16 -1 (-3625 4850)(-3200 4850);
WIRE 16 -1 (-3625 4250)(-3200 4250);
WIRE 16 -1 (-3625 4300)(-3200 4300);
WIRE 16 -1 (-3625 5450)(-3200 5450);
WIRE 16 -1 (-3625 5500)(-3200 5500);
WIRE 16 -1 (-3625 5600)(-3200 5600);
WIRE 16 -1 (-3625 5650)(-3200 5650);
WIRE 16 -1 (-3625 5700)(-3200 5700);
WIRE 16 -1 (-3625 5750)(-3200 5750);
WIRE 16 -1 (-3625 5800)(-3200 5800);
WIRE 16 -1 (-3625 5850)(-3200 5850);
WIRE 16 -1 (-3625 5900)(-3200 5900);
WIRE 16 -1 (-3625 5150)(-3200 5150);
WIRE 16 -1 (-3625 5950)(-3200 5950);
WIRE 16 -1 (-3625 5200)(-3200 5200);
WIRE 16 -1 (-3625 5250)(-3200 5250);
WIRE 16 -1 (-3625 5300)(-3200 5300);
WIRE 16 -1 (-3625 5350)(-3200 5350);
WIRE 16 -1 (-3625 5400)(-3200 5400);
QUIT
